FILE_TYPE = MACRO_DRAWING;
SET COLOR_WIRE YELLOW;
SET COLOR_PROP MONO;
SET COLOR_DOT WHITE;
SET COLOR_ARC YELLOW;
SET COLOR_BODY GREEN;
SET COLOR_NOTE MONO;
SET PROP_DISPLAY VALUE;
SET PAGE_NUMBER P37;
FORCEADD PVCCIN_CPU0..1
(-7125 4350);
FORCEPROP 3 LASTPIN (-7125 4300) SIG_NAME PVCCIN_CPU0\g
J 0
(-7115 4310);
DISPLAY 0.659574 (-7115 4310);
PAINT MONO (-7115 4310);
DISPLAY INVISIBLE (-7115 4310);
FORCEPROP 1 LAST BODY_TYPE PLUMBING
J 0
(-7170 4307);
DISPLAY 0.340426 (-7170 4307);
PAINT GREEN (-7170 4307);
DISPLAY INVISIBLE (-7170 4307);
FORCEPROP 1 LAST VOLTAGE 2.0V
J 0
(-7170 4307);
DISPLAY 0.340426 (-7170 4307);
PAINT SKYBLUE (-7170 4307);
DISPLAY INVISIBLE (-7170 4307);
FORCEPROP 2 LAST CDS_LIB mstr_symbols
J 0
(-7125 4350);
PAINT ORANGE (-7125 4350);
DISPLAY INVISIBLE (-7125 4350);
FORCEPROP 1 LAST PATH I295
J 0
(-7075 4375);
DISPLAY 0.872340 (-7075 4375);
PAINT AQUA (-7075 4375);
DISPLAY INVISIBLE (-7075 4375);
FORCEPROP 1 LAST HDL_POWER PVCCIN_CPU0
J 1
(-7125 4400);
DISPLAY 0.872340 (-7125 4400);
PAINT GREEN (-7125 4400);
DISPLAY INVISIBLE (-7125 4400);
FORCEADD PVCCIN_CPU0..1
(-5250 4275);
FORCEPROP 3 LASTPIN (-5250 4225) SIG_NAME PVCCIN_CPU0\g
J 0
(-5240 4235);
DISPLAY 0.659574 (-5240 4235);
PAINT MONO (-5240 4235);
DISPLAY INVISIBLE (-5240 4235);
FORCEPROP 1 LAST VOLTAGE 2.0V
J 0
(-5295 4232);
DISPLAY 0.340426 (-5295 4232);
PAINT SKYBLUE (-5295 4232);
DISPLAY INVISIBLE (-5295 4232);
FORCEPROP 2 LAST CDS_LIB mstr_symbols
J 0
(-5250 4275);
PAINT ORANGE (-5250 4275);
DISPLAY INVISIBLE (-5250 4275);
FORCEPROP 1 LAST BODY_TYPE PLUMBING
J 0
(-5295 4232);
DISPLAY 0.340426 (-5295 4232);
PAINT GREEN (-5295 4232);
DISPLAY INVISIBLE (-5295 4232);
FORCEPROP 1 LAST PATH I296
J 0
(-5200 4300);
DISPLAY 0.872340 (-5200 4300);
PAINT AQUA (-5200 4300);
DISPLAY INVISIBLE (-5200 4300);
FORCEPROP 1 LAST HDL_POWER PVCCIN_CPU0
J 1
(-5250 4325);
DISPLAY 0.872340 (-5250 4325);
PAINT GREEN (-5250 4325);
DISPLAY INVISIBLE (-5250 4325);
FORCEADD OFFPAGE..2
(-750 725);
FORCEPROP 2 LAST $XR0 204 
J 0
(-561 725);
DISPLAY 0.638298 (-561 725);
PAINT MONO (-561 725);
FORCEPROP 1 LAST COMMENT_BODY TRUE
J 0
(-795 630);
DISPLAY 1.170213 (-795 630);
PAINT GREEN (-795 630);
DISPLAY INVISIBLE (-795 630);
FORCEPROP 2 LAST CDS_LIB mstr_standard
J 0
(-750 725);
PAINT ORANGE (-750 725);
DISPLAY INVISIBLE (-750 725);
FORCEPROP 2 LAST PATH I298
J 0
(-575 800);
DISPLAY 1.021277 (-575 800);
PAINT ORANGE (-575 800);
DISPLAY INVISIBLE (-575 800);
FORCEPROP 1 LAST OFFPAGE TRUE
J 0
(-425 600);
DISPLAY 1.170213 (-425 600);
PAINT GREEN (-425 600);
DISPLAY INVISIBLE (-425 600);
FORCEADD OFFPAGE..2
(-750 775);
FORCEPROP 2 LAST $XR0 204 
J 0
(-561 775);
DISPLAY 0.638298 (-561 775);
PAINT MONO (-561 775);
FORCEPROP 1 LAST COMMENT_BODY TRUE
J 0
(-795 680);
DISPLAY 1.170213 (-795 680);
PAINT GREEN (-795 680);
DISPLAY INVISIBLE (-795 680);
FORCEPROP 2 LAST PATH I299
J 0
(-575 850);
DISPLAY 1.021277 (-575 850);
PAINT ORANGE (-575 850);
DISPLAY INVISIBLE (-575 850);
FORCEPROP 2 LAST CDS_LIB mstr_standard
J 0
(-750 775);
PAINT ORANGE (-750 775);
DISPLAY INVISIBLE (-750 775);
FORCEPROP 1 LAST OFFPAGE TRUE
J 0
(-425 650);
DISPLAY 1.170213 (-425 650);
PAINT GREEN (-425 650);
DISPLAY INVISIBLE (-425 650);
FORCEADD PVCCIN_CPU0..1
(-3375 4350);
FORCEPROP 3 LASTPIN (-3375 4300) SIG_NAME PVCCIN_CPU0\g
J 0
(-3365 4310);
DISPLAY 0.659574 (-3365 4310);
PAINT MONO (-3365 4310);
DISPLAY INVISIBLE (-3365 4310);
FORCEPROP 1 LAST VOLTAGE 2.0V
J 0
(-3420 4307);
DISPLAY 0.340426 (-3420 4307);
PAINT SKYBLUE (-3420 4307);
DISPLAY INVISIBLE (-3420 4307);
FORCEPROP 1 LAST BODY_TYPE PLUMBING
J 0
(-3420 4307);
DISPLAY 0.340426 (-3420 4307);
PAINT GREEN (-3420 4307);
DISPLAY INVISIBLE (-3420 4307);
FORCEPROP 2 LAST CDS_LIB mstr_symbols
J 0
(-3375 4350);
PAINT ORANGE (-3375 4350);
DISPLAY INVISIBLE (-3375 4350);
FORCEPROP 1 LAST HDL_POWER PVCCIN_CPU0
J 1
(-3375 4400);
DISPLAY 0.872340 (-3375 4400);
PAINT GREEN (-3375 4400);
DISPLAY INVISIBLE (-3375 4400);
FORCEPROP 1 LAST PATH I300
J 0
(-3325 4375);
DISPLAY 0.872340 (-3325 4375);
PAINT AQUA (-3325 4375);
DISPLAY INVISIBLE (-3325 4375);
FORCEADD PVCCIN_CPU0..1
(-1500 4325);
FORCEPROP 3 LASTPIN (-1500 4275) SIG_NAME PVCCIN_CPU0\g
J 0
(-1490 4285);
DISPLAY 0.659574 (-1490 4285);
PAINT MONO (-1490 4285);
DISPLAY INVISIBLE (-1490 4285);
FORCEPROP 1 LAST BODY_TYPE PLUMBING
J 0
(-1545 4282);
DISPLAY 0.340426 (-1545 4282);
PAINT GREEN (-1545 4282);
DISPLAY INVISIBLE (-1545 4282);
FORCEPROP 1 LAST VOLTAGE 2.0V
J 0
(-1545 4282);
DISPLAY 0.340426 (-1545 4282);
PAINT SKYBLUE (-1545 4282);
DISPLAY INVISIBLE (-1545 4282);
FORCEPROP 2 LAST CDS_LIB mstr_symbols
J 0
(-1500 4325);
PAINT ORANGE (-1500 4325);
DISPLAY INVISIBLE (-1500 4325);
FORCEPROP 1 LAST PATH I301
J 0
(-1450 4350);
DISPLAY 0.872340 (-1450 4350);
PAINT AQUA (-1450 4350);
DISPLAY INVISIBLE (-1450 4350);
FORCEPROP 1 LAST HDL_POWER PVCCIN_CPU0
J 1
(-1500 4375);
DISPLAY 0.872340 (-1500 4375);
PAINT GREEN (-1500 4375);
DISPLAY INVISIBLE (-1500 4375);
FORCEADD GND..1
(-375 525);
FORCEPROP 3 LASTPIN (-375 575) SIG_NAME GND\g
J 0
(-365 585);
DISPLAY 0.659574 (-365 585);
PAINT MONO (-365 585);
DISPLAY INVISIBLE (-365 585);
FORCEPROP 1 LAST BODY_TYPE PLUMBING
J 0
(-420 482);
DISPLAY 0.340426 (-420 482);
PAINT GREEN (-420 482);
DISPLAY INVISIBLE (-420 482);
FORCEPROP 1 LAST VOLTAGE 0.0V
J 0
(-420 482);
DISPLAY 0.340426 (-420 482);
PAINT SKYBLUE (-420 482);
DISPLAY INVISIBLE (-420 482);
FORCEPROP 1 LAST SIZE 1B
J 0
(-300 475);
DISPLAY 1.170213 (-300 475);
PAINT AQUA (-300 475);
DISPLAY INVISIBLE (-300 475);
FORCEPROP 1 LAST HDL_POWER GND
J 0
(-375 675);
DISPLAY 1.170213 (-375 675);
PAINT GREEN (-375 675);
DISPLAY INVISIBLE (-375 675);
FORCEPROP 1 LAST PATH I302
J 0
(-300 525);
DISPLAY 0.872340 (-300 525);
PAINT AQUA (-300 525);
DISPLAY INVISIBLE (-300 525);
FORCEPROP 2 LAST CDS_LIB mstr_symbols
J 0
(-375 525);
PAINT ORANGE (-375 525);
DISPLAY INVISIBLE (-375 525);
FORCEADD RES..2
(-375 750);
FORCEPROP 1 LASTPIN (-375 650) $PN 2
J 0
(-370 660);
DISPLAY 0.617021 (-370 660);
PAINT ORANGE (-370 660);
FORCEPROP 1 LASTPIN (-375 850) $PN 1
J 0
(-370 812);
DISPLAY 0.617021 (-370 812);
PAINT ORANGE (-370 812);
FORCEPROP 1 LAST WATTAGE 1/16W
J 0
(-335 725);
DISPLAY 0.617021 (-335 725);
PAINT SKYBLUE (-335 725);
FORCEPROP 1 LAST MATERIAL CHIP
J 0
(-335 675);
DISPLAY 0.617021 (-335 675);
PAINT SKYBLUE (-335 675);
FORCEPROP 1 LAST PACK_TYPE 0402
J 0
(-335 575);
DISPLAY 0.617021 (-335 575);
PAINT SKYBLUE (-335 575);
FORCEPROP 1 LAST TOLERANCE 0.1%
J 0
(-330 775);
DISPLAY 0.617021 (-330 775);
PAINT SKYBLUE (-330 775);
FORCEPROP 1 LAST VALUE 249
J 0
(-330 825);
DISPLAY 0.617021 (-330 825);
PAINT SKYBLUE (-330 825);
FORCEPROP 1 LAST PART_NUMBER G85996-031
J 0
(-335 625);
DISPLAY 0.617021 (-335 625);
PAINT BLUE (-335 625);
FORCEPROP 1 LAST LOCATION R5D5
J 0
(-330 875);
DISPLAY 0.617021 (-330 875);
PAINT AQUA (-330 875);
FORCEPROP 2 LAST CDS_LIB mstr_discrete
J 0
(-375 750);
PAINT ORANGE (-375 750);
DISPLAY INVISIBLE (-375 750);
FORCEPROP 2 LAST CDS_LOCATION R5D5
J 0
(-330 875);
DISPLAY 0.617021 (-330 875);
PAINT AQUA (-330 875);
DISPLAY INVISIBLE (-330 875);
FORCEPROP 2 LAST ROOM CPU0
J 0
(-325 925);
DISPLAY 1.021277 (-325 925);
PAINT ORANGE (-325 925);
DISPLAY INVISIBLE (-325 925);
FORCEPROP 1 LAST PATH I303
J 0
(-325 925);
DISPLAY 0.978723 (-325 925);
PAINT WHITE (-325 925);
DISPLAY INVISIBLE (-325 925);
FORCEPROP 2 LAST SEC 1
J 0
(-325 975);
DISPLAY 0.680851 (-325 975);
PAINT MONO (-325 975);
DISPLAY INVISIBLE (-325 975);
FORCEPROP 2 LAST SEC_TYPE 0402
J 0
(-325 975);
DISPLAY 1.021277 (-325 975);
PAINT ORANGE (-325 975);
DISPLAY INVISIBLE (-325 975);
FORCEPROP 2 LAST BOM_COST PROC_SOCKET
J 0
(-325 975);
DISPLAY 1.021277 (-325 975);
PAINT ORANGE (-325 975);
DISPLAY INVISIBLE (-325 975);
FORCEADD PVCCIN_CPU0..1
(-775 1625);
FORCEPROP 3 LASTPIN (-775 1575) SIG_NAME PVCCIN_CPU0\g
J 0
(-765 1585);
DISPLAY 0.659574 (-765 1585);
PAINT MONO (-765 1585);
DISPLAY INVISIBLE (-765 1585);
FORCEPROP 1 LAST HDL_POWER PVCCIN_CPU0
J 1
(-775 1675);
DISPLAY 0.872340 (-775 1675);
PAINT GREEN (-775 1675);
DISPLAY INVISIBLE (-775 1675);
FORCEPROP 1 LAST PATH I305
J 0
(-725 1650);
DISPLAY 0.872340 (-725 1650);
PAINT AQUA (-725 1650);
DISPLAY INVISIBLE (-725 1650);
FORCEPROP 1 LAST BODY_TYPE PLUMBING
J 0
(-820 1582);
DISPLAY 0.340426 (-820 1582);
PAINT GREEN (-820 1582);
DISPLAY INVISIBLE (-820 1582);
FORCEPROP 2 LAST CDS_LIB mstr_symbols
J 0
(-775 1625);
PAINT ORANGE (-775 1625);
DISPLAY INVISIBLE (-775 1625);
FORCEPROP 1 LAST VOLTAGE 2.0V
J 0
(-820 1582);
DISPLAY 0.340426 (-820 1582);
PAINT SKYBLUE (-820 1582);
DISPLAY INVISIBLE (-820 1582);
FORCEADD RES..2
(-775 1350);
FORCEPROP 1 LASTPIN (-775 1250) $PN 2
J 0
(-770 1260);
DISPLAY 0.617021 (-770 1260);
PAINT ORANGE (-770 1260);
FORCEPROP 1 LASTPIN (-775 1450) $PN 1
J 0
(-770 1412);
DISPLAY 0.617021 (-770 1412);
PAINT ORANGE (-770 1412);
FORCEPROP 1 LAST WATTAGE 1/10W
J 0
(-735 1325);
DISPLAY 0.617021 (-735 1325);
PAINT SKYBLUE (-735 1325);
FORCEPROP 1 LAST MATERIAL CHIP
J 0
(-735 1275);
DISPLAY 0.617021 (-735 1275);
PAINT SKYBLUE (-735 1275);
FORCEPROP 1 LAST LOCATION R5P1
J 0
(-725 1475);
DISPLAY 0.617021 (-725 1475);
PAINT AQUA (-725 1475);
FORCEPROP 1 LAST VALUE 100.0K
J 0
(-730 1425);
DISPLAY 0.617021 (-730 1425);
PAINT SKYBLUE (-730 1425);
FORCEPROP 1 LAST PACK_TYPE 0603
J 0
(-735 1175);
DISPLAY 0.617021 (-735 1175);
PAINT SKYBLUE (-735 1175);
FORCEPROP 1 LAST TOLERANCE 1%
J 0
(-730 1375);
DISPLAY 0.617021 (-730 1375);
PAINT SKYBLUE (-730 1375);
FORCEPROP 1 LAST PART_NUMBER G22026-050
J 0
(-735 1225);
DISPLAY 0.617021 (-735 1225);
PAINT BLUE (-735 1225);
FORCEPROP 2 LAST CDS_LIB mstr_discrete
J 0
(-775 1350);
PAINT ORANGE (-775 1350);
DISPLAY INVISIBLE (-775 1350);
FORCEPROP 2 LAST CDS_LOCATION R5P1
J 0
(-725 1475);
DISPLAY 0.617021 (-725 1475);
PAINT AQUA (-725 1475);
DISPLAY INVISIBLE (-725 1475);
FORCEPROP 2 LAST ROOM CPU0
J 0
(-700 1450);
DISPLAY 1.021277 (-700 1450);
PAINT ORANGE (-700 1450);
DISPLAY INVISIBLE (-700 1450);
FORCEPROP 1 LAST PATH I309
J 0
(-725 1525);
DISPLAY 0.978723 (-725 1525);
PAINT WHITE (-725 1525);
DISPLAY INVISIBLE (-725 1525);
FORCEPROP 2 LAST BOM_COST PROC_SOCKET
J 0
(-700 1500);
DISPLAY 1.021277 (-700 1500);
PAINT ORANGE (-700 1500);
DISPLAY INVISIBLE (-700 1500);
FORCEPROP 2 LAST SEC 1
J 0
(-725 1575);
DISPLAY 0.680851 (-725 1575);
PAINT MONO (-725 1575);
DISPLAY INVISIBLE (-725 1575);
FORCEPROP 2 LAST SEC_TYPE 0603
J 0
(-725 1575);
DISPLAY 1.021277 (-725 1575);
PAINT ORANGE (-725 1575);
DISPLAY INVISIBLE (-725 1575);
FORCEADD SKX_EXT_B..18
(-6200 2475);
FORCEPROP 2 LASTPIN (-6900 775) $PN BF85
J 2
(-6910 785);
DISPLAY 0.617021 (-6910 785);
PAINT ORANGE (-6910 785);
FORCEPROP 2 LASTPIN (-6900 825) $PN BF83
J 2
(-6910 835);
DISPLAY 0.617021 (-6910 835);
PAINT ORANGE (-6910 835);
FORCEPROP 2 LASTPIN (-6900 875) $PN BF81
J 2
(-6910 885);
DISPLAY 0.617021 (-6910 885);
PAINT ORANGE (-6910 885);
FORCEPROP 2 LASTPIN (-6900 925) $PN BF79
J 2
(-6910 935);
DISPLAY 0.617021 (-6910 935);
PAINT ORANGE (-6910 935);
FORCEPROP 2 LASTPIN (-6900 975) $PN BF77
J 2
(-6910 985);
DISPLAY 0.617021 (-6910 985);
PAINT ORANGE (-6910 985);
FORCEPROP 1 LAST PART_NUMBER TBD
J 0
(-6850 575);
DISPLAY 0.617021 (-6850 575);
PAINT BLUE (-6850 575);
FORCEPROP 2 LASTPIN (-6900 1025) $PN BF75
J 2
(-6910 1035);
DISPLAY 0.617021 (-6910 1035);
PAINT ORANGE (-6910 1035);
FORCEPROP 2 LASTPIN (-6900 1075) $PN BF73
J 2
(-6910 1085);
DISPLAY 0.617021 (-6910 1085);
PAINT ORANGE (-6910 1085);
FORCEPROP 2 LASTPIN (-6900 1125) $PN BF61
J 2
(-6910 1135);
DISPLAY 0.617021 (-6910 1135);
PAINT ORANGE (-6910 1135);
FORCEPROP 2 LASTPIN (-6900 1175) $PN BE84
J 2
(-6910 1185);
DISPLAY 0.617021 (-6910 1185);
PAINT ORANGE (-6910 1185);
FORCEPROP 2 LASTPIN (-6900 1225) $PN BE82
J 2
(-6910 1235);
DISPLAY 0.617021 (-6910 1235);
PAINT ORANGE (-6910 1235);
FORCEPROP 2 LASTPIN (-6900 1275) $PN BE80
J 2
(-6910 1285);
DISPLAY 0.617021 (-6910 1285);
PAINT ORANGE (-6910 1285);
FORCEPROP 2 LASTPIN (-6900 1325) $PN BE78
J 2
(-6910 1335);
DISPLAY 0.617021 (-6910 1335);
PAINT ORANGE (-6910 1335);
FORCEPROP 2 LASTPIN (-6900 1375) $PN BE76
J 2
(-6910 1385);
DISPLAY 0.617021 (-6910 1385);
PAINT ORANGE (-6910 1385);
FORCEPROP 2 LASTPIN (-6900 1425) $PN BE74
J 2
(-6910 1435);
DISPLAY 0.617021 (-6910 1435);
PAINT ORANGE (-6910 1435);
FORCEPROP 2 LASTPIN (-6900 1475) $PN BE72
J 2
(-6910 1485);
DISPLAY 0.617021 (-6910 1485);
PAINT ORANGE (-6910 1485);
FORCEPROP 2 LASTPIN (-6900 1525) $PN BE62
J 2
(-6910 1535);
DISPLAY 0.617021 (-6910 1535);
PAINT ORANGE (-6910 1535);
FORCEPROP 2 LASTPIN (-6900 1575) $PN BE60
J 2
(-6910 1585);
DISPLAY 0.617021 (-6910 1585);
PAINT ORANGE (-6910 1585);
FORCEPROP 2 LASTPIN (-6900 1625) $PN BD85
J 2
(-6910 1635);
DISPLAY 0.617021 (-6910 1635);
PAINT ORANGE (-6910 1635);
FORCEPROP 2 LASTPIN (-6900 1675) $PN BD83
J 2
(-6910 1685);
DISPLAY 0.617021 (-6910 1685);
PAINT ORANGE (-6910 1685);
FORCEPROP 2 LASTPIN (-6900 1725) $PN BD81
J 2
(-6910 1735);
DISPLAY 0.617021 (-6910 1735);
PAINT ORANGE (-6910 1735);
FORCEPROP 2 LASTPIN (-6900 1775) $PN BD79
J 2
(-6910 1785);
DISPLAY 0.617021 (-6910 1785);
PAINT ORANGE (-6910 1785);
FORCEPROP 2 LASTPIN (-6900 1825) $PN BD77
J 2
(-6910 1835);
DISPLAY 0.617021 (-6910 1835);
PAINT ORANGE (-6910 1835);
FORCEPROP 2 LASTPIN (-6900 1875) $PN BD75
J 2
(-6910 1885);
DISPLAY 0.617021 (-6910 1885);
PAINT ORANGE (-6910 1885);
FORCEPROP 2 LASTPIN (-6900 1925) $PN BD73
J 2
(-6910 1935);
DISPLAY 0.617021 (-6910 1935);
PAINT ORANGE (-6910 1935);
FORCEPROP 2 LASTPIN (-6900 1975) $PN BD61
J 2
(-6910 1985);
DISPLAY 0.617021 (-6910 1985);
PAINT ORANGE (-6910 1985);
FORCEPROP 2 LASTPIN (-6900 2025) $PN BC84
J 2
(-6910 2035);
DISPLAY 0.617021 (-6910 2035);
PAINT ORANGE (-6910 2035);
FORCEPROP 2 LASTPIN (-6900 2075) $PN BC62
J 2
(-6910 2085);
DISPLAY 0.617021 (-6910 2085);
PAINT ORANGE (-6910 2085);
FORCEPROP 2 LASTPIN (-6900 2125) $PN BC60
J 2
(-6910 2135);
DISPLAY 0.617021 (-6910 2135);
PAINT ORANGE (-6910 2135);
FORCEPROP 2 LASTPIN (-6900 2175) $PN BB85
J 2
(-6910 2185);
DISPLAY 0.617021 (-6910 2185);
PAINT ORANGE (-6910 2185);
FORCEPROP 2 LASTPIN (-6900 2225) $PN BB61
J 2
(-6910 2235);
DISPLAY 0.617021 (-6910 2235);
PAINT ORANGE (-6910 2235);
FORCEPROP 2 LASTPIN (-6900 2275) $PN BA60
J 2
(-6910 2285);
DISPLAY 0.617021 (-6910 2285);
PAINT ORANGE (-6910 2285);
FORCEPROP 2 LASTPIN (-6900 2325) $PN AY61
J 2
(-6910 2335);
DISPLAY 0.617021 (-6910 2335);
PAINT ORANGE (-6910 2335);
FORCEPROP 2 LASTPIN (-6900 2375) $PN AW60
J 2
(-6910 2385);
DISPLAY 0.617021 (-6910 2385);
PAINT ORANGE (-6910 2385);
FORCEPROP 2 LASTPIN (-6900 2425) $PN AV61
J 2
(-6910 2435);
DISPLAY 0.617021 (-6910 2435);
PAINT ORANGE (-6910 2435);
FORCEPROP 2 LASTPIN (-6900 2475) $PN AV59
J 2
(-6910 2485);
DISPLAY 0.617021 (-6910 2485);
PAINT ORANGE (-6910 2485);
FORCEPROP 2 LASTPIN (-6900 2525) $PN AU60
J 2
(-6910 2535);
DISPLAY 0.617021 (-6910 2535);
PAINT ORANGE (-6910 2535);
FORCEPROP 2 LASTPIN (-6900 2575) $PN AU58
J 2
(-6910 2585);
DISPLAY 0.617021 (-6910 2585);
PAINT ORANGE (-6910 2585);
FORCEPROP 2 LASTPIN (-6900 2625) $PN AT59
J 2
(-6910 2635);
DISPLAY 0.617021 (-6910 2635);
PAINT ORANGE (-6910 2635);
FORCEPROP 2 LASTPIN (-6900 2675) $PN AT57
J 2
(-6910 2685);
DISPLAY 0.617021 (-6910 2685);
PAINT ORANGE (-6910 2685);
FORCEPROP 2 LASTPIN (-6900 2725) $PN AR58
J 2
(-6910 2735);
DISPLAY 0.617021 (-6910 2735);
PAINT ORANGE (-6910 2735);
FORCEPROP 2 LASTPIN (-6900 2775) $PN AR56
J 2
(-6910 2785);
DISPLAY 0.617021 (-6910 2785);
PAINT ORANGE (-6910 2785);
FORCEPROP 2 LASTPIN (-6900 2825) $PN AP57
J 2
(-6910 2835);
DISPLAY 0.617021 (-6910 2835);
PAINT ORANGE (-6910 2835);
FORCEPROP 2 LASTPIN (-6900 2875) $PN AP55
J 2
(-6910 2885);
DISPLAY 0.617021 (-6910 2885);
PAINT ORANGE (-6910 2885);
FORCEPROP 2 LASTPIN (-6900 2925) $PN AN56
J 2
(-6910 2935);
DISPLAY 0.617021 (-6910 2935);
PAINT ORANGE (-6910 2935);
FORCEPROP 2 LASTPIN (-6900 2975) $PN AN54
J 2
(-6910 2985);
DISPLAY 0.617021 (-6910 2985);
PAINT ORANGE (-6910 2985);
FORCEPROP 2 LASTPIN (-6900 3025) $PN AN32
J 2
(-6910 3035);
DISPLAY 0.617021 (-6910 3035);
PAINT ORANGE (-6910 3035);
FORCEPROP 2 LASTPIN (-6900 3075) $PN AM55
J 2
(-6910 3085);
DISPLAY 0.617021 (-6910 3085);
PAINT ORANGE (-6910 3085);
FORCEPROP 2 LASTPIN (-6900 3125) $PN AM53
J 2
(-6910 3135);
DISPLAY 0.617021 (-6910 3135);
PAINT ORANGE (-6910 3135);
FORCEPROP 2 LASTPIN (-6900 3175) $PN AM33
J 2
(-6910 3185);
DISPLAY 0.617021 (-6910 3185);
PAINT ORANGE (-6910 3185);
FORCEPROP 2 LASTPIN (-6900 3225) $PN AL54
J 2
(-6910 3235);
DISPLAY 0.617021 (-6910 3235);
PAINT ORANGE (-6910 3235);
FORCEPROP 2 LASTPIN (-6900 3275) $PN AL52
J 2
(-6910 3285);
DISPLAY 0.617021 (-6910 3285);
PAINT ORANGE (-6910 3285);
FORCEPROP 2 LASTPIN (-6900 3325) $PN AL50
J 2
(-6910 3335);
DISPLAY 0.617021 (-6910 3335);
PAINT ORANGE (-6910 3335);
FORCEPROP 2 LASTPIN (-6900 3375) $PN AL48
J 2
(-6910 3385);
DISPLAY 0.617021 (-6910 3385);
PAINT ORANGE (-6910 3385);
FORCEPROP 2 LASTPIN (-6900 3425) $PN AL46
J 2
(-6910 3435);
DISPLAY 0.617021 (-6910 3435);
PAINT ORANGE (-6910 3435);
FORCEPROP 2 LASTPIN (-6900 3475) $PN AL34
J 2
(-6910 3485);
DISPLAY 0.617021 (-6910 3485);
PAINT ORANGE (-6910 3485);
FORCEPROP 2 LASTPIN (-6900 3525) $PN AK53
J 2
(-6910 3535);
DISPLAY 0.617021 (-6910 3535);
PAINT ORANGE (-6910 3535);
FORCEPROP 2 LASTPIN (-6900 3575) $PN AK51
J 2
(-6910 3585);
DISPLAY 0.617021 (-6910 3585);
PAINT ORANGE (-6910 3585);
FORCEPROP 2 LASTPIN (-6900 3625) $PN AK49
J 2
(-6910 3635);
DISPLAY 0.617021 (-6910 3635);
PAINT ORANGE (-6910 3635);
FORCEPROP 2 LASTPIN (-6900 3675) $PN AK47
J 2
(-6910 3685);
DISPLAY 0.617021 (-6910 3685);
PAINT ORANGE (-6910 3685);
FORCEPROP 2 LASTPIN (-6900 3725) $PN AK45
J 2
(-6910 3735);
DISPLAY 0.617021 (-6910 3735);
PAINT ORANGE (-6910 3735);
FORCEPROP 2 LASTPIN (-6900 3775) $PN AK35
J 2
(-6910 3785);
DISPLAY 0.617021 (-6910 3785);
PAINT ORANGE (-6910 3785);
FORCEPROP 2 LASTPIN (-6900 3825) $PN AJ36
J 2
(-6910 3835);
DISPLAY 0.617021 (-6910 3835);
PAINT ORANGE (-6910 3835);
FORCEPROP 2 LASTPIN (-6900 3875) $PN AH41
J 2
(-6910 3885);
DISPLAY 0.617021 (-6910 3885);
PAINT ORANGE (-6910 3885);
FORCEPROP 2 LASTPIN (-6900 3925) $PN AH39
J 2
(-6910 3935);
DISPLAY 0.617021 (-6910 3935);
PAINT ORANGE (-6910 3935);
FORCEPROP 2 LASTPIN (-6900 3975) $PN AH37
J 2
(-6910 3985);
DISPLAY 0.617021 (-6910 3985);
PAINT ORANGE (-6910 3985);
FORCEPROP 2 LASTPIN (-6900 4025) $PN AG42
J 2
(-6910 4035);
DISPLAY 0.617021 (-6910 4035);
PAINT ORANGE (-6910 4035);
FORCEPROP 2 LASTPIN (-5500 775) $PN BN78
J 0
(-5490 785);
DISPLAY 0.617021 (-5490 785);
PAINT ORANGE (-5490 785);
FORCEPROP 2 LASTPIN (-5500 825) $PN BN76
J 0
(-5490 835);
DISPLAY 0.617021 (-5490 835);
PAINT ORANGE (-5490 835);
FORCEPROP 2 LASTPIN (-5500 875) $PN BN74
J 0
(-5490 885);
DISPLAY 0.617021 (-5490 885);
PAINT ORANGE (-5490 885);
FORCEPROP 2 LASTPIN (-5500 925) $PN BN72
J 0
(-5490 935);
DISPLAY 0.617021 (-5490 935);
PAINT ORANGE (-5490 935);
FORCEPROP 2 LASTPIN (-5500 975) $PN BN70
J 0
(-5490 985);
DISPLAY 0.617021 (-5490 985);
PAINT ORANGE (-5490 985);
FORCEPROP 2 LASTPIN (-5500 1025) $PN BN68
J 0
(-5490 1035);
DISPLAY 0.617021 (-5490 1035);
PAINT ORANGE (-5490 1035);
FORCEPROP 2 LASTPIN (-5500 1075) $PN BN66
J 0
(-5490 1085);
DISPLAY 0.617021 (-5490 1085);
PAINT ORANGE (-5490 1085);
FORCEPROP 2 LASTPIN (-5500 1125) $PN BN64
J 0
(-5490 1135);
DISPLAY 0.617021 (-5490 1135);
PAINT ORANGE (-5490 1135);
FORCEPROP 2 LASTPIN (-5500 1175) $PN BN62
J 0
(-5490 1185);
DISPLAY 0.617021 (-5490 1185);
PAINT ORANGE (-5490 1185);
FORCEPROP 2 LASTPIN (-5500 1225) $PN BN60
J 0
(-5490 1235);
DISPLAY 0.617021 (-5490 1235);
PAINT ORANGE (-5490 1235);
FORCEPROP 2 LASTPIN (-5500 1275) $PN BM83
J 0
(-5490 1285);
DISPLAY 0.617021 (-5490 1285);
PAINT ORANGE (-5490 1285);
FORCEPROP 2 LASTPIN (-5500 1325) $PN BM81
J 0
(-5490 1335);
DISPLAY 0.617021 (-5490 1335);
PAINT ORANGE (-5490 1335);
FORCEPROP 2 LASTPIN (-5500 1375) $PN BM79
J 0
(-5490 1385);
DISPLAY 0.617021 (-5490 1385);
PAINT ORANGE (-5490 1385);
FORCEPROP 2 LASTPIN (-5500 1425) $PN BM77
J 0
(-5490 1435);
DISPLAY 0.617021 (-5490 1435);
PAINT ORANGE (-5490 1435);
FORCEPROP 2 LASTPIN (-5500 1475) $PN BM75
J 0
(-5490 1485);
DISPLAY 0.617021 (-5490 1485);
PAINT ORANGE (-5490 1485);
FORCEPROP 2 LASTPIN (-5500 1525) $PN BM73
J 0
(-5490 1535);
DISPLAY 0.617021 (-5490 1535);
PAINT ORANGE (-5490 1535);
FORCEPROP 2 LASTPIN (-5500 1575) $PN BM71
J 0
(-5490 1585);
DISPLAY 0.617021 (-5490 1585);
PAINT ORANGE (-5490 1585);
FORCEPROP 2 LASTPIN (-5500 1625) $PN BM69
J 0
(-5490 1635);
DISPLAY 0.617021 (-5490 1635);
PAINT ORANGE (-5490 1635);
FORCEPROP 2 LASTPIN (-5500 1675) $PN BM67
J 0
(-5490 1685);
DISPLAY 0.617021 (-5490 1685);
PAINT ORANGE (-5490 1685);
FORCEPROP 2 LASTPIN (-5500 1725) $PN BM65
J 0
(-5490 1735);
DISPLAY 0.617021 (-5490 1735);
PAINT ORANGE (-5490 1735);
FORCEPROP 2 LASTPIN (-5500 1775) $PN BM63
J 0
(-5490 1785);
DISPLAY 0.617021 (-5490 1785);
PAINT ORANGE (-5490 1785);
FORCEPROP 2 LASTPIN (-5500 1825) $PN BM61
J 0
(-5490 1835);
DISPLAY 0.617021 (-5490 1835);
PAINT ORANGE (-5490 1835);
FORCEPROP 2 LASTPIN (-5500 1875) $PN BL84
J 0
(-5490 1885);
DISPLAY 0.617021 (-5490 1885);
PAINT ORANGE (-5490 1885);
FORCEPROP 2 LASTPIN (-5500 1925) $PN BL62
J 0
(-5490 1935);
DISPLAY 0.617021 (-5490 1935);
PAINT ORANGE (-5490 1935);
FORCEPROP 2 LASTPIN (-5500 1975) $PN BL60
J 0
(-5490 1985);
DISPLAY 0.617021 (-5490 1985);
PAINT ORANGE (-5490 1985);
FORCEPROP 2 LASTPIN (-5500 2025) $PN BK83
J 0
(-5490 2035);
DISPLAY 0.617021 (-5490 2035);
PAINT ORANGE (-5490 2035);
FORCEPROP 2 LASTPIN (-5500 2075) $PN BK81
J 0
(-5490 2085);
DISPLAY 0.617021 (-5490 2085);
PAINT ORANGE (-5490 2085);
FORCEPROP 2 LASTPIN (-5500 2125) $PN BK79
J 0
(-5490 2135);
DISPLAY 0.617021 (-5490 2135);
PAINT ORANGE (-5490 2135);
FORCEPROP 2 LASTPIN (-5500 2175) $PN BK77
J 0
(-5490 2185);
DISPLAY 0.617021 (-5490 2185);
PAINT ORANGE (-5490 2185);
FORCEPROP 2 LASTPIN (-5500 2225) $PN BK75
J 0
(-5490 2235);
DISPLAY 0.617021 (-5490 2235);
PAINT ORANGE (-5490 2235);
FORCEPROP 2 LASTPIN (-5500 2275) $PN BK73
J 0
(-5490 2285);
DISPLAY 0.617021 (-5490 2285);
PAINT ORANGE (-5490 2285);
FORCEPROP 2 LASTPIN (-5500 2325) $PN BK71
J 0
(-5490 2335);
DISPLAY 0.617021 (-5490 2335);
PAINT ORANGE (-5490 2335);
FORCEPROP 2 LASTPIN (-5500 2375) $PN BK69
J 0
(-5490 2385);
DISPLAY 0.617021 (-5490 2385);
PAINT ORANGE (-5490 2385);
FORCEPROP 2 LASTPIN (-5500 2425) $PN BK67
J 0
(-5490 2435);
DISPLAY 0.617021 (-5490 2435);
PAINT ORANGE (-5490 2435);
FORCEPROP 2 LASTPIN (-5500 2475) $PN BK65
J 0
(-5490 2485);
DISPLAY 0.617021 (-5490 2485);
PAINT ORANGE (-5490 2485);
FORCEPROP 2 LASTPIN (-5500 2525) $PN BK63
J 0
(-5490 2535);
DISPLAY 0.617021 (-5490 2535);
PAINT ORANGE (-5490 2535);
FORCEPROP 2 LASTPIN (-5500 2575) $PN BK61
J 0
(-5490 2585);
DISPLAY 0.617021 (-5490 2585);
PAINT ORANGE (-5490 2585);
FORCEPROP 2 LASTPIN (-5500 2625) $PN BJ84
J 0
(-5490 2635);
DISPLAY 0.617021 (-5490 2635);
PAINT ORANGE (-5490 2635);
FORCEPROP 2 LASTPIN (-5500 2675) $PN BJ82
J 0
(-5490 2685);
DISPLAY 0.617021 (-5490 2685);
PAINT ORANGE (-5490 2685);
FORCEPROP 2 LASTPIN (-5500 2725) $PN BJ80
J 0
(-5490 2735);
DISPLAY 0.617021 (-5490 2735);
PAINT ORANGE (-5490 2735);
FORCEPROP 2 LASTPIN (-5500 2775) $PN BJ78
J 0
(-5490 2785);
DISPLAY 0.617021 (-5490 2785);
PAINT ORANGE (-5490 2785);
FORCEPROP 2 LASTPIN (-5500 2825) $PN BJ76
J 0
(-5490 2835);
DISPLAY 0.617021 (-5490 2835);
PAINT ORANGE (-5490 2835);
FORCEPROP 2 LASTPIN (-5500 2875) $PN BJ74
J 0
(-5490 2885);
DISPLAY 0.617021 (-5490 2885);
PAINT ORANGE (-5490 2885);
FORCEPROP 2 LASTPIN (-5500 2925) $PN BJ72
J 0
(-5490 2935);
DISPLAY 0.617021 (-5490 2935);
PAINT ORANGE (-5490 2935);
FORCEPROP 2 LASTPIN (-5500 2975) $PN BJ70
J 0
(-5490 2985);
DISPLAY 0.617021 (-5490 2985);
PAINT ORANGE (-5490 2985);
FORCEPROP 2 LASTPIN (-5500 3025) $PN BJ68
J 0
(-5490 3035);
DISPLAY 0.617021 (-5490 3035);
PAINT ORANGE (-5490 3035);
FORCEPROP 2 LASTPIN (-5500 3075) $PN BJ66
J 0
(-5490 3085);
DISPLAY 0.617021 (-5490 3085);
PAINT ORANGE (-5490 3085);
FORCEPROP 2 LASTPIN (-5500 3125) $PN BJ64
J 0
(-5490 3135);
DISPLAY 0.617021 (-5490 3135);
PAINT ORANGE (-5490 3135);
FORCEPROP 2 LASTPIN (-5500 3175) $PN BJ62
J 0
(-5490 3185);
DISPLAY 0.617021 (-5490 3185);
PAINT ORANGE (-5490 3185);
FORCEPROP 2 LASTPIN (-5500 3225) $PN BJ60
J 0
(-5490 3235);
DISPLAY 0.617021 (-5490 3235);
PAINT ORANGE (-5490 3235);
FORCEPROP 2 LASTPIN (-5500 3275) $PN BH83
J 0
(-5490 3285);
DISPLAY 0.617021 (-5490 3285);
PAINT ORANGE (-5490 3285);
FORCEPROP 2 LASTPIN (-5500 3325) $PN BH81
J 0
(-5490 3335);
DISPLAY 0.617021 (-5490 3335);
PAINT ORANGE (-5490 3335);
FORCEPROP 2 LASTPIN (-5500 3375) $PN BH79
J 0
(-5490 3385);
DISPLAY 0.617021 (-5490 3385);
PAINT ORANGE (-5490 3385);
FORCEPROP 2 LASTPIN (-5500 3425) $PN BH77
J 0
(-5490 3435);
DISPLAY 0.617021 (-5490 3435);
PAINT ORANGE (-5490 3435);
FORCEPROP 2 LASTPIN (-5500 3475) $PN BH75
J 0
(-5490 3485);
DISPLAY 0.617021 (-5490 3485);
PAINT ORANGE (-5490 3485);
FORCEPROP 2 LASTPIN (-5500 3525) $PN BH73
J 0
(-5490 3535);
DISPLAY 0.617021 (-5490 3535);
PAINT ORANGE (-5490 3535);
FORCEPROP 2 LASTPIN (-5500 3575) $PN BH71
J 0
(-5490 3585);
DISPLAY 0.617021 (-5490 3585);
PAINT ORANGE (-5490 3585);
FORCEPROP 2 LASTPIN (-5500 3625) $PN BH69
J 0
(-5490 3635);
DISPLAY 0.617021 (-5490 3635);
PAINT ORANGE (-5490 3635);
FORCEPROP 2 LASTPIN (-5500 3675) $PN BH67
J 0
(-5490 3685);
DISPLAY 0.617021 (-5490 3685);
PAINT ORANGE (-5490 3685);
FORCEPROP 2 LASTPIN (-5500 3725) $PN BH65
J 0
(-5490 3735);
DISPLAY 0.617021 (-5490 3735);
PAINT ORANGE (-5490 3735);
FORCEPROP 2 LASTPIN (-5500 3775) $PN BH63
J 0
(-5490 3785);
DISPLAY 0.617021 (-5490 3785);
PAINT ORANGE (-5490 3785);
FORCEPROP 2 LASTPIN (-5500 3825) $PN BH61
J 0
(-5490 3835);
DISPLAY 0.617021 (-5490 3835);
PAINT ORANGE (-5490 3835);
FORCEPROP 2 LASTPIN (-5500 3875) $PN BG84
J 0
(-5490 3885);
DISPLAY 0.617021 (-5490 3885);
PAINT ORANGE (-5490 3885);
FORCEPROP 2 LASTPIN (-5500 3925) $PN BG70
J 0
(-5490 3935);
DISPLAY 0.617021 (-5490 3935);
PAINT ORANGE (-5490 3935);
FORCEPROP 2 LASTPIN (-5500 3975) $PN BG68
J 0
(-5490 3985);
DISPLAY 0.617021 (-5490 3985);
PAINT ORANGE (-5490 3985);
FORCEPROP 2 LASTPIN (-5500 4025) $PN BG66
J 0
(-5490 4035);
DISPLAY 0.617021 (-5490 4035);
PAINT ORANGE (-5490 4035);
FORCEPROP 2 LASTPIN (-5500 4075) $PN BG64
J 0
(-5490 4085);
DISPLAY 0.617021 (-5490 4085);
PAINT ORANGE (-5490 4085);
FORCEPROP 2 LASTPIN (-6900 4075) $PN AG40
J 2
(-6910 4085);
DISPLAY 0.617021 (-6910 4085);
PAINT ORANGE (-6910 4085);
FORCEPROP 2 LASTPIN (-6900 4175) $PN AF43
J 2
(-6910 4185);
DISPLAY 0.617021 (-6910 4185);
PAINT ORANGE (-6910 4185);
FORCEPROP 2 LASTPIN (-6900 4125) $PN AG38
J 2
(-6910 4135);
DISPLAY 0.617021 (-6910 4135);
PAINT ORANGE (-6910 4135);
FORCEPROP 1 LAST MATERIAL IC
J 0
(-6850 4375);
DISPLAY 0.617021 (-6850 4375);
PAINT SKYBLUE (-6850 4375);
FORCEPROP 1 LAST LOCATION U5D1
J 0
(-6850 4425);
DISPLAY 0.617021 (-6850 4425);
PAINT AQUA (-6850 4425);
FORCEPROP 2 LASTPIN (-5500 4125) $PN BG62
J 0
(-5490 4135);
DISPLAY 0.617021 (-5490 4135);
PAINT ORANGE (-5490 4135);
FORCEPROP 2 LASTPIN (-5500 4175) $PN BG60
J 0
(-5490 4185);
DISPLAY 0.617021 (-5490 4185);
PAINT ORANGE (-5490 4185);
FORCEPROP 2 LAST CDS_LIB chpset_lib
J 0
(-6200 2475);
PAINT ORANGE (-6200 2475);
DISPLAY INVISIBLE (-6200 2475);
FORCEPROP 1 LAST PACK_TYPE BGA1
J 0
(-6850 4475);
PAINT SKYBLUE (-6850 4475);
DISPLAY INVISIBLE (-6850 4475);
FORCEPROP 0 LAST ROOM CPU0
J 0
(-6850 4525);
DISPLAY 1.021277 (-6850 4525);
PAINT ORANGE (-6850 4525);
DISPLAY INVISIBLE (-6850 4525);
FORCEPROP 2 LAST CDS_LOCATION U5D1
J 0
(-6850 4425);
DISPLAY 0.617021 (-6850 4425);
PAINT AQUA (-6850 4425);
DISPLAY INVISIBLE (-6850 4425);
FORCEPROP 2 LAST SEC 18
J 0
(-6850 4475);
DISPLAY 0.680851 (-6850 4475);
PAINT MONO (-6850 4475);
DISPLAY INVISIBLE (-6850 4475);
FORCEPROP 2 LAST SEC_TYPE BGA1
J 0
(-6850 4475);
DISPLAY 1.021277 (-6850 4475);
PAINT ORANGE (-6850 4475);
DISPLAY INVISIBLE (-6850 4475);
FORCEPROP 1 LAST PATH I310
J 0
(-6200 4375);
PAINT GREEN (-6200 4375);
DISPLAY INVISIBLE (-6200 4375);
FORCEADD SKX_EXT_B..19
(-2425 2475);
FORCEPROP 2 LASTPIN (-3125 775) $PN BY83
J 2
(-3135 785);
DISPLAY 0.617021 (-3135 785);
PAINT ORANGE (-3135 785);
FORCEPROP 2 LASTPIN (-3125 825) $PN BY81
J 2
(-3135 835);
DISPLAY 0.617021 (-3135 835);
PAINT ORANGE (-3135 835);
FORCEPROP 2 LASTPIN (-3125 875) $PN BY79
J 2
(-3135 885);
DISPLAY 0.617021 (-3135 885);
PAINT ORANGE (-3135 885);
FORCEPROP 2 LASTPIN (-3125 925) $PN BY77
J 2
(-3135 935);
DISPLAY 0.617021 (-3135 935);
PAINT ORANGE (-3135 935);
FORCEPROP 2 LASTPIN (-3125 975) $PN BY75
J 2
(-3135 985);
DISPLAY 0.617021 (-3135 985);
PAINT ORANGE (-3135 985);
FORCEPROP 2 LASTPIN (-3125 1225) $PN BW68
J 2
(-3135 1235);
DISPLAY 0.617021 (-3135 1235);
PAINT ORANGE (-3135 1235);
FORCEPROP 2 LASTPIN (-3125 1175) $PN BW70
J 2
(-3135 1185);
DISPLAY 0.617021 (-3135 1185);
PAINT ORANGE (-3135 1185);
FORCEPROP 2 LASTPIN (-3125 1125) $PN BW84
J 2
(-3135 1135);
DISPLAY 0.617021 (-3135 1135);
PAINT ORANGE (-3135 1135);
FORCEPROP 2 LASTPIN (-3125 1075) $PN BY61
J 2
(-3135 1085);
DISPLAY 0.617021 (-3135 1085);
PAINT ORANGE (-3135 1085);
FORCEPROP 2 LASTPIN (-3125 1025) $PN BY73
J 2
(-3135 1035);
DISPLAY 0.617021 (-3135 1035);
PAINT ORANGE (-3135 1035);
FORCEPROP 2 LASTPIN (-3125 1475) $PN BV83
J 2
(-3135 1485);
DISPLAY 0.617021 (-3135 1485);
PAINT ORANGE (-3135 1485);
FORCEPROP 2 LASTPIN (-3125 1425) $PN BW60
J 2
(-3135 1435);
DISPLAY 0.617021 (-3135 1435);
PAINT ORANGE (-3135 1435);
FORCEPROP 2 LASTPIN (-3125 1375) $PN BW62
J 2
(-3135 1385);
DISPLAY 0.617021 (-3135 1385);
PAINT ORANGE (-3135 1385);
FORCEPROP 2 LASTPIN (-3125 1325) $PN BW64
J 2
(-3135 1335);
DISPLAY 0.617021 (-3135 1335);
PAINT ORANGE (-3135 1335);
FORCEPROP 2 LASTPIN (-3125 1275) $PN BW66
J 2
(-3135 1285);
DISPLAY 0.617021 (-3135 1285);
PAINT ORANGE (-3135 1285);
FORCEPROP 2 LASTPIN (-3125 1525) $PN BV81
J 2
(-3135 1535);
DISPLAY 0.617021 (-3135 1535);
PAINT ORANGE (-3135 1535);
FORCEPROP 2 LASTPIN (-3125 1725) $PN BV73
J 2
(-3135 1735);
DISPLAY 0.617021 (-3135 1735);
PAINT ORANGE (-3135 1735);
FORCEPROP 2 LASTPIN (-3125 1675) $PN BV75
J 2
(-3135 1685);
DISPLAY 0.617021 (-3135 1685);
PAINT ORANGE (-3135 1685);
FORCEPROP 2 LASTPIN (-3125 1625) $PN BV77
J 2
(-3135 1635);
DISPLAY 0.617021 (-3135 1635);
PAINT ORANGE (-3135 1635);
FORCEPROP 2 LASTPIN (-3125 1575) $PN BV79
J 2
(-3135 1585);
DISPLAY 0.617021 (-3135 1585);
PAINT ORANGE (-3135 1585);
FORCEPROP 2 LASTPIN (-3125 1775) $PN BV71
J 2
(-3135 1785);
DISPLAY 0.617021 (-3135 1785);
PAINT ORANGE (-3135 1785);
FORCEPROP 2 LASTPIN (-3125 1975) $PN BV63
J 2
(-3135 1985);
DISPLAY 0.617021 (-3135 1985);
PAINT ORANGE (-3135 1985);
FORCEPROP 2 LASTPIN (-3125 1925) $PN BV65
J 2
(-3135 1935);
DISPLAY 0.617021 (-3135 1935);
PAINT ORANGE (-3135 1935);
FORCEPROP 2 LASTPIN (-3125 1875) $PN BV67
J 2
(-3135 1885);
DISPLAY 0.617021 (-3135 1885);
PAINT ORANGE (-3135 1885);
FORCEPROP 2 LASTPIN (-3125 1825) $PN BV69
J 2
(-3135 1835);
DISPLAY 0.617021 (-3135 1835);
PAINT ORANGE (-3135 1835);
FORCEPROP 1 LAST PART_NUMBER TBD
J 0
(-3075 525);
DISPLAY 0.617021 (-3075 525);
PAINT BLUE (-3075 525);
FORCEPROP 2 LASTPIN (-3125 2025) $PN BV61
J 2
(-3135 2035);
DISPLAY 0.617021 (-3135 2035);
PAINT ORANGE (-3135 2035);
FORCEPROP 2 LASTPIN (-3125 2225) $PN BU78
J 2
(-3135 2235);
DISPLAY 0.617021 (-3135 2235);
PAINT ORANGE (-3135 2235);
FORCEPROP 2 LASTPIN (-3125 2175) $PN BU80
J 2
(-3135 2185);
DISPLAY 0.617021 (-3135 2185);
PAINT ORANGE (-3135 2185);
FORCEPROP 2 LASTPIN (-3125 2125) $PN BU82
J 2
(-3135 2135);
DISPLAY 0.617021 (-3135 2135);
PAINT ORANGE (-3135 2135);
FORCEPROP 2 LASTPIN (-3125 2075) $PN BU84
J 2
(-3135 2085);
DISPLAY 0.617021 (-3135 2085);
PAINT ORANGE (-3135 2085);
FORCEPROP 2 LASTPIN (-3125 2275) $PN BU76
J 2
(-3135 2285);
DISPLAY 0.617021 (-3135 2285);
PAINT ORANGE (-3135 2285);
FORCEPROP 2 LASTPIN (-3125 2475) $PN BU68
J 2
(-3135 2485);
DISPLAY 0.617021 (-3135 2485);
PAINT ORANGE (-3135 2485);
FORCEPROP 2 LASTPIN (-3125 2425) $PN BU70
J 2
(-3135 2435);
DISPLAY 0.617021 (-3135 2435);
PAINT ORANGE (-3135 2435);
FORCEPROP 2 LASTPIN (-3125 2375) $PN BU72
J 2
(-3135 2385);
DISPLAY 0.617021 (-3135 2385);
PAINT ORANGE (-3135 2385);
FORCEPROP 2 LASTPIN (-3125 2325) $PN BU74
J 2
(-3135 2335);
DISPLAY 0.617021 (-3135 2335);
PAINT ORANGE (-3135 2335);
FORCEPROP 2 LASTPIN (-3125 2525) $PN BU66
J 2
(-3135 2535);
DISPLAY 0.617021 (-3135 2535);
PAINT ORANGE (-3135 2535);
FORCEPROP 2 LASTPIN (-3125 2775) $PN BT81
J 2
(-3135 2785);
DISPLAY 0.617021 (-3135 2785);
PAINT ORANGE (-3135 2785);
FORCEPROP 2 LASTPIN (-3125 2725) $PN BT83
J 2
(-3135 2735);
DISPLAY 0.617021 (-3135 2735);
PAINT ORANGE (-3135 2735);
FORCEPROP 2 LASTPIN (-3125 2675) $PN BU60
J 2
(-3135 2685);
DISPLAY 0.617021 (-3135 2685);
PAINT ORANGE (-3135 2685);
FORCEPROP 2 LASTPIN (-3125 2625) $PN BU62
J 2
(-3135 2635);
DISPLAY 0.617021 (-3135 2635);
PAINT ORANGE (-3135 2635);
FORCEPROP 2 LASTPIN (-3125 2575) $PN BU64
J 2
(-3135 2585);
DISPLAY 0.617021 (-3135 2585);
PAINT ORANGE (-3135 2585);
FORCEPROP 2 LASTPIN (-3125 3025) $PN BT71
J 2
(-3135 3035);
DISPLAY 0.617021 (-3135 3035);
PAINT ORANGE (-3135 3035);
FORCEPROP 2 LASTPIN (-3125 2975) $PN BT73
J 2
(-3135 2985);
DISPLAY 0.617021 (-3135 2985);
PAINT ORANGE (-3135 2985);
FORCEPROP 2 LASTPIN (-3125 2925) $PN BT75
J 2
(-3135 2935);
DISPLAY 0.617021 (-3135 2935);
PAINT ORANGE (-3135 2935);
FORCEPROP 2 LASTPIN (-3125 2875) $PN BT77
J 2
(-3135 2885);
DISPLAY 0.617021 (-3135 2885);
PAINT ORANGE (-3135 2885);
FORCEPROP 2 LASTPIN (-3125 2825) $PN BT79
J 2
(-3135 2835);
DISPLAY 0.617021 (-3135 2835);
PAINT ORANGE (-3135 2835);
FORCEPROP 2 LASTPIN (-3125 3275) $PN BT61
J 2
(-3135 3285);
DISPLAY 0.617021 (-3135 3285);
PAINT ORANGE (-3135 3285);
FORCEPROP 2 LASTPIN (-3125 3225) $PN BT63
J 2
(-3135 3235);
DISPLAY 0.617021 (-3135 3235);
PAINT ORANGE (-3135 3235);
FORCEPROP 2 LASTPIN (-3125 3175) $PN BT65
J 2
(-3135 3185);
DISPLAY 0.617021 (-3135 3185);
PAINT ORANGE (-3135 3185);
FORCEPROP 2 LASTPIN (-3125 3125) $PN BT67
J 2
(-3135 3135);
DISPLAY 0.617021 (-3135 3135);
PAINT ORANGE (-3135 3135);
FORCEPROP 2 LASTPIN (-3125 3075) $PN BT69
J 2
(-3135 3085);
DISPLAY 0.617021 (-3135 3085);
PAINT ORANGE (-3135 3085);
FORCEPROP 2 LASTPIN (-3125 3525) $PN BP81
J 2
(-3135 3535);
DISPLAY 0.617021 (-3135 3535);
PAINT ORANGE (-3135 3535);
FORCEPROP 2 LASTPIN (-3125 3475) $PN BP83
J 2
(-3135 3485);
DISPLAY 0.617021 (-3135 3485);
PAINT ORANGE (-3135 3485);
FORCEPROP 2 LASTPIN (-3125 3425) $PN BR60
J 2
(-3135 3435);
DISPLAY 0.617021 (-3135 3435);
PAINT ORANGE (-3135 3435);
FORCEPROP 2 LASTPIN (-3125 3375) $PN BR62
J 2
(-3135 3385);
DISPLAY 0.617021 (-3135 3385);
PAINT ORANGE (-3135 3385);
FORCEPROP 2 LASTPIN (-3125 3325) $PN BR84
J 2
(-3135 3335);
DISPLAY 0.617021 (-3135 3335);
PAINT ORANGE (-3135 3335);
FORCEPROP 2 LASTPIN (-3125 3775) $PN BP71
J 2
(-3135 3785);
DISPLAY 0.617021 (-3135 3785);
PAINT ORANGE (-3135 3785);
FORCEPROP 2 LASTPIN (-3125 3725) $PN BP73
J 2
(-3135 3735);
DISPLAY 0.617021 (-3135 3735);
PAINT ORANGE (-3135 3735);
FORCEPROP 2 LASTPIN (-3125 3675) $PN BP75
J 2
(-3135 3685);
DISPLAY 0.617021 (-3135 3685);
PAINT ORANGE (-3135 3685);
FORCEPROP 2 LASTPIN (-3125 3625) $PN BP77
J 2
(-3135 3635);
DISPLAY 0.617021 (-3135 3635);
PAINT ORANGE (-3135 3635);
FORCEPROP 2 LASTPIN (-3125 3575) $PN BP79
J 2
(-3135 3585);
DISPLAY 0.617021 (-3135 3585);
PAINT ORANGE (-3135 3585);
FORCEPROP 2 LASTPIN (-3125 3825) $PN BP69
J 2
(-3135 3835);
DISPLAY 0.617021 (-3135 3835);
PAINT ORANGE (-3135 3835);
FORCEPROP 2 LASTPIN (-3125 4025) $PN BP61
J 2
(-3135 4035);
DISPLAY 0.617021 (-3135 4035);
PAINT ORANGE (-3135 4035);
FORCEPROP 2 LASTPIN (-3125 3975) $PN BP63
J 2
(-3135 3985);
DISPLAY 0.617021 (-3135 3985);
PAINT ORANGE (-3135 3985);
FORCEPROP 2 LASTPIN (-3125 3925) $PN BP65
J 2
(-3135 3935);
DISPLAY 0.617021 (-3135 3935);
PAINT ORANGE (-3135 3935);
FORCEPROP 2 LASTPIN (-3125 3875) $PN BP67
J 2
(-3135 3885);
DISPLAY 0.617021 (-3135 3885);
PAINT ORANGE (-3135 3885);
FORCEPROP 2 LASTPIN (-1725 725) $PN AY85
J 0
(-1715 735);
DISPLAY 0.617021 (-1715 735);
PAINT ORANGE (-1715 735);
FORCEPROP 2 LASTPIN (-1725 875) $PN AD41
J 0
(-1715 885);
DISPLAY 0.617021 (-1715 885);
PAINT ORANGE (-1715 885);
FORCEPROP 2 LASTPIN (-1725 975) $PN AW86
J 0
(-1715 985);
DISPLAY 0.617021 (-1715 985);
PAINT ORANGE (-1715 985);
FORCEPROP 2 LASTPIN (-1725 775) $PN BA86
J 0
(-1715 785);
DISPLAY 0.617021 (-1715 785);
PAINT ORANGE (-1715 785);
FORCEPROP 2 LASTPIN (-1725 1175) $PN CY49
J 0
(-1715 1185);
DISPLAY 0.617021 (-1715 1185);
PAINT ORANGE (-1715 1185);
FORCEPROP 2 LASTPIN (-1725 1225) $PN CY47
J 0
(-1715 1235);
DISPLAY 0.617021 (-1715 1235);
PAINT ORANGE (-1715 1235);
FORCEPROP 2 LASTPIN (-1725 1075) $PN AV85
J 0
(-1715 1085);
DISPLAY 0.617021 (-1715 1085);
PAINT ORANGE (-1715 1085);
FORCEPROP 2 LASTPIN (-1725 1475) $PN CU54
J 0
(-1715 1485);
DISPLAY 0.617021 (-1715 1485);
PAINT ORANGE (-1715 1485);
FORCEPROP 2 LASTPIN (-1725 1425) $PN CV51
J 0
(-1715 1435);
DISPLAY 0.617021 (-1715 1435);
PAINT ORANGE (-1715 1435);
FORCEPROP 2 LASTPIN (-1725 1375) $PN CW46
J 0
(-1715 1385);
DISPLAY 0.617021 (-1715 1385);
PAINT ORANGE (-1715 1385);
FORCEPROP 2 LASTPIN (-1725 1325) $PN CW48
J 0
(-1715 1335);
DISPLAY 0.617021 (-1715 1335);
PAINT ORANGE (-1715 1335);
FORCEPROP 2 LASTPIN (-1725 1275) $PN CW50
J 0
(-1715 1285);
DISPLAY 0.617021 (-1715 1285);
PAINT ORANGE (-1715 1285);
FORCEPROP 2 LASTPIN (-1725 1525) $PN CU52
J 0
(-1715 1535);
DISPLAY 0.617021 (-1715 1535);
PAINT ORANGE (-1715 1535);
FORCEPROP 2 LASTPIN (-1725 1725) $PN CT55
J 0
(-1715 1735);
DISPLAY 0.617021 (-1715 1735);
PAINT ORANGE (-1715 1735);
FORCEPROP 2 LASTPIN (-1725 1675) $PN CU38
J 0
(-1715 1685);
DISPLAY 0.617021 (-1715 1685);
PAINT ORANGE (-1715 1685);
FORCEPROP 2 LASTPIN (-1725 1625) $PN CU40
J 0
(-1715 1635);
DISPLAY 0.617021 (-1715 1635);
PAINT ORANGE (-1715 1635);
FORCEPROP 2 LASTPIN (-1725 1575) $PN CU42
J 0
(-1715 1585);
DISPLAY 0.617021 (-1715 1585);
PAINT ORANGE (-1715 1585);
FORCEPROP 2 LASTPIN (-1725 1775) $PN CT53
J 0
(-1715 1785);
DISPLAY 0.617021 (-1715 1785);
PAINT ORANGE (-1715 1785);
FORCEPROP 2 LASTPIN (-1725 1975) $PN CR56
J 0
(-1715 1985);
DISPLAY 0.617021 (-1715 1985);
PAINT ORANGE (-1715 1985);
FORCEPROP 2 LASTPIN (-1725 1925) $PN CT37
J 0
(-1715 1935);
DISPLAY 0.617021 (-1715 1935);
PAINT ORANGE (-1715 1935);
FORCEPROP 2 LASTPIN (-1725 1875) $PN CT39
J 0
(-1715 1885);
DISPLAY 0.617021 (-1715 1885);
PAINT ORANGE (-1715 1885);
FORCEPROP 2 LASTPIN (-1725 1825) $PN CT41
J 0
(-1715 1835);
DISPLAY 0.617021 (-1715 1835);
PAINT ORANGE (-1715 1835);
FORCEPROP 2 LASTPIN (-1725 2025) $PN CR54
J 0
(-1715 2035);
DISPLAY 0.617021 (-1715 2035);
PAINT ORANGE (-1715 2035);
FORCEPROP 2 LASTPIN (-1725 2225) $PN CP33
J 0
(-1715 2235);
DISPLAY 0.617021 (-1715 2235);
PAINT ORANGE (-1715 2235);
FORCEPROP 2 LASTPIN (-1725 2175) $PN CP55
J 0
(-1715 2185);
DISPLAY 0.617021 (-1715 2185);
PAINT ORANGE (-1715 2185);
FORCEPROP 2 LASTPIN (-1725 2125) $PN CP57
J 0
(-1715 2135);
DISPLAY 0.617021 (-1715 2135);
PAINT ORANGE (-1715 2135);
FORCEPROP 2 LASTPIN (-1725 2075) $PN CR34
J 0
(-1715 2085);
DISPLAY 0.617021 (-1715 2085);
PAINT ORANGE (-1715 2085);
FORCEPROP 2 LASTPIN (-1725 2275) $PN CN58
J 0
(-1715 2285);
DISPLAY 0.617021 (-1715 2285);
PAINT ORANGE (-1715 2285);
FORCEPROP 2 LASTPIN (-1725 2475) $PN CL60
J 0
(-1715 2485);
DISPLAY 0.617021 (-1715 2485);
PAINT ORANGE (-1715 2485);
FORCEPROP 2 LASTPIN (-1725 2425) $PN CM57
J 0
(-1715 2435);
DISPLAY 0.617021 (-1715 2435);
PAINT ORANGE (-1715 2435);
FORCEPROP 2 LASTPIN (-1725 2375) $PN CM59
J 0
(-1715 2385);
DISPLAY 0.617021 (-1715 2385);
PAINT ORANGE (-1715 2385);
FORCEPROP 2 LASTPIN (-1725 2325) $PN CN56
J 0
(-1715 2335);
DISPLAY 0.617021 (-1715 2335);
PAINT ORANGE (-1715 2335);
FORCEPROP 2 LASTPIN (-1725 2525) $PN CL58
J 0
(-1715 2535);
DISPLAY 0.617021 (-1715 2535);
PAINT ORANGE (-1715 2535);
FORCEPROP 2 LASTPIN (-1725 2775) $PN CH61
J 0
(-1715 2785);
DISPLAY 0.617021 (-1715 2785);
PAINT ORANGE (-1715 2785);
FORCEPROP 2 LASTPIN (-1725 2725) $PN CH85
J 0
(-1715 2735);
DISPLAY 0.617021 (-1715 2735);
PAINT ORANGE (-1715 2735);
FORCEPROP 2 LASTPIN (-1725 2675) $PN CJ60
J 0
(-1715 2685);
DISPLAY 0.617021 (-1715 2685);
PAINT ORANGE (-1715 2685);
FORCEPROP 2 LASTPIN (-1725 2625) $PN CK59
J 0
(-1715 2635);
DISPLAY 0.617021 (-1715 2635);
PAINT ORANGE (-1715 2635);
FORCEPROP 2 LASTPIN (-1725 2575) $PN CK61
J 0
(-1715 2585);
DISPLAY 0.617021 (-1715 2585);
PAINT ORANGE (-1715 2585);
FORCEPROP 2 LASTPIN (-1725 3025) $PN CE84
J 0
(-1715 3035);
DISPLAY 0.617021 (-1715 3035);
PAINT ORANGE (-1715 3035);
FORCEPROP 2 LASTPIN (-1725 2975) $PN CF61
J 0
(-1715 2985);
DISPLAY 0.617021 (-1715 2985);
PAINT ORANGE (-1715 2985);
FORCEPROP 2 LASTPIN (-1725 2925) $PN CF85
J 0
(-1715 2935);
DISPLAY 0.617021 (-1715 2935);
PAINT ORANGE (-1715 2935);
FORCEPROP 2 LASTPIN (-1725 2875) $PN CG60
J 0
(-1715 2885);
DISPLAY 0.617021 (-1715 2885);
PAINT ORANGE (-1715 2885);
FORCEPROP 2 LASTPIN (-1725 2825) $PN CG84
J 0
(-1715 2835);
DISPLAY 0.617021 (-1715 2835);
PAINT ORANGE (-1715 2835);
FORCEPROP 2 LASTPIN (-1725 3275) $PN CC84
J 0
(-1715 3285);
DISPLAY 0.617021 (-1715 3285);
PAINT ORANGE (-1715 3285);
FORCEPROP 2 LASTPIN (-1725 3225) $PN CD61
J 0
(-1715 3235);
DISPLAY 0.617021 (-1715 3235);
PAINT ORANGE (-1715 3235);
FORCEPROP 2 LASTPIN (-1725 3175) $PN CD83
J 0
(-1715 3185);
DISPLAY 0.617021 (-1715 3185);
PAINT ORANGE (-1715 3185);
FORCEPROP 2 LASTPIN (-1725 3125) $PN CD85
J 0
(-1715 3135);
DISPLAY 0.617021 (-1715 3135);
PAINT ORANGE (-1715 3135);
FORCEPROP 2 LASTPIN (-1725 3075) $PN CE60
J 0
(-1715 3085);
DISPLAY 0.617021 (-1715 3085);
PAINT ORANGE (-1715 3085);
FORCEPROP 2 LASTPIN (-1725 3525) $PN CB79
J 0
(-1715 3535);
DISPLAY 0.617021 (-1715 3535);
PAINT ORANGE (-1715 3535);
FORCEPROP 2 LASTPIN (-1725 3475) $PN CB81
J 0
(-1715 3485);
DISPLAY 0.617021 (-1715 3485);
PAINT ORANGE (-1715 3485);
FORCEPROP 2 LASTPIN (-1725 3425) $PN CB83
J 0
(-1715 3435);
DISPLAY 0.617021 (-1715 3435);
PAINT ORANGE (-1715 3435);
FORCEPROP 2 LASTPIN (-1725 3375) $PN CC60
J 0
(-1715 3385);
DISPLAY 0.617021 (-1715 3385);
PAINT ORANGE (-1715 3385);
FORCEPROP 2 LASTPIN (-1725 3325) $PN CC62
J 0
(-1715 3335);
DISPLAY 0.617021 (-1715 3335);
PAINT ORANGE (-1715 3335);
FORCEPROP 2 LASTPIN (-1725 3775) $PN CA84
J 0
(-1715 3785);
DISPLAY 0.617021 (-1715 3785);
PAINT ORANGE (-1715 3785);
FORCEPROP 2 LASTPIN (-1725 3725) $PN CB61
J 0
(-1715 3735);
DISPLAY 0.617021 (-1715 3735);
PAINT ORANGE (-1715 3735);
FORCEPROP 2 LASTPIN (-1725 3675) $PN CB73
J 0
(-1715 3685);
DISPLAY 0.617021 (-1715 3685);
PAINT ORANGE (-1715 3685);
FORCEPROP 2 LASTPIN (-1725 3625) $PN CB75
J 0
(-1715 3635);
DISPLAY 0.617021 (-1715 3635);
PAINT ORANGE (-1715 3635);
FORCEPROP 2 LASTPIN (-1725 3575) $PN CB77
J 0
(-1715 3585);
DISPLAY 0.617021 (-1715 3585);
PAINT ORANGE (-1715 3585);
FORCEPROP 2 LASTPIN (-1725 3825) $PN CA82
J 0
(-1715 3835);
DISPLAY 0.617021 (-1715 3835);
PAINT ORANGE (-1715 3835);
FORCEPROP 2 LASTPIN (-1725 4025) $PN CA74
J 0
(-1715 4035);
DISPLAY 0.617021 (-1715 4035);
PAINT ORANGE (-1715 4035);
FORCEPROP 2 LASTPIN (-1725 3975) $PN CA76
J 0
(-1715 3985);
DISPLAY 0.617021 (-1715 3985);
PAINT ORANGE (-1715 3985);
FORCEPROP 2 LASTPIN (-1725 3925) $PN CA78
J 0
(-1715 3935);
DISPLAY 0.617021 (-1715 3935);
PAINT ORANGE (-1715 3935);
FORCEPROP 2 LASTPIN (-1725 3875) $PN CA80
J 0
(-1715 3885);
DISPLAY 0.617021 (-1715 3885);
PAINT ORANGE (-1715 3885);
FORCEPROP 2 LASTPIN (-1725 4075) $PN CA72
J 0
(-1715 4085);
DISPLAY 0.617021 (-1715 4085);
PAINT ORANGE (-1715 4085);
FORCEPROP 2 LASTPIN (-3125 4075) $PN BN84
J 2
(-3135 4085);
DISPLAY 0.617021 (-3135 4085);
PAINT ORANGE (-3135 4085);
FORCEPROP 2 LASTPIN (-3125 4125) $PN BN82
J 2
(-3135 4135);
DISPLAY 0.617021 (-3135 4135);
PAINT ORANGE (-3135 4135);
FORCEPROP 2 LASTPIN (-3125 4175) $PN BN80
J 2
(-3135 4185);
DISPLAY 0.617021 (-3135 4185);
PAINT ORANGE (-3135 4185);
FORCEPROP 1 LAST MATERIAL IC
J 0
(-3075 4375);
DISPLAY 0.617021 (-3075 4375);
PAINT SKYBLUE (-3075 4375);
FORCEPROP 1 LAST LOCATION U5D1
J 0
(-3075 4425);
DISPLAY 0.617021 (-3075 4425);
PAINT AQUA (-3075 4425);
FORCEPROP 2 LASTPIN (-1725 4125) $PN CA62
J 0
(-1715 4135);
DISPLAY 0.617021 (-1715 4135);
PAINT ORANGE (-1715 4135);
FORCEPROP 2 LASTPIN (-1725 4175) $PN CA60
J 0
(-1715 4185);
DISPLAY 0.617021 (-1715 4185);
PAINT ORANGE (-1715 4185);
FORCEPROP 2 LAST CDS_LIB chpset_lib
J 0
(-2425 2475);
PAINT ORANGE (-2425 2475);
DISPLAY INVISIBLE (-2425 2475);
FORCEPROP 0 LAST ROOM CPU0
J 0
(-3075 4525);
DISPLAY 1.021277 (-3075 4525);
PAINT ORANGE (-3075 4525);
DISPLAY INVISIBLE (-3075 4525);
FORCEPROP 2 LAST CDS_LOCATION U5D1
J 0
(-3075 4425);
DISPLAY 0.617021 (-3075 4425);
PAINT AQUA (-3075 4425);
DISPLAY INVISIBLE (-3075 4425);
FORCEPROP 2 LAST SEC 19
J 0
(-3075 4475);
DISPLAY 0.680851 (-3075 4475);
PAINT MONO (-3075 4475);
DISPLAY INVISIBLE (-3075 4475);
FORCEPROP 2 LAST SEC_TYPE BGA1
J 0
(-3075 4475);
DISPLAY 1.021277 (-3075 4475);
PAINT ORANGE (-3075 4475);
DISPLAY INVISIBLE (-3075 4475);
FORCEPROP 1 LAST PACK_TYPE BGA1
J 0
(-3075 4475);
PAINT SKYBLUE (-3075 4475);
DISPLAY INVISIBLE (-3075 4475);
FORCEPROP 1 LAST PATH I311
J 0
(-2425 4375);
PAINT GREEN (-2425 4375);
DISPLAY INVISIBLE (-2425 4375);
FORCEADD RES..2
(-375 1125);
FORCEPROP 1 LAST PACK_TYPE 0402
J 0
(-335 950);
DISPLAY 0.617021 (-335 950);
PAINT SKYBLUE (-335 950);
FORCEPROP 1 LAST PART_NUMBER G21796-066
J 0
(-335 1000);
DISPLAY 0.617021 (-335 1000);
PAINT BLUE (-335 1000);
FORCEPROP 1 LASTPIN (-375 1025) $PN 2
J 0
(-370 1035);
DISPLAY 0.617021 (-370 1035);
PAINT ORANGE (-370 1035);
FORCEPROP 1 LAST TOLERANCE 1%
J 0
(-330 1150);
DISPLAY 0.617021 (-330 1150);
PAINT SKYBLUE (-330 1150);
FORCEPROP 1 LASTPIN (-375 1225) $PN 1
J 0
(-370 1187);
DISPLAY 0.617021 (-370 1187);
PAINT ORANGE (-370 1187);
FORCEPROP 1 LAST WATTAGE 1/16W
J 0
(-335 1100);
DISPLAY 0.617021 (-335 1100);
PAINT SKYBLUE (-335 1100);
FORCEPROP 1 LAST VALUE 10.0
J 0
(-330 1200);
DISPLAY 0.617021 (-330 1200);
PAINT SKYBLUE (-330 1200);
FORCEPROP 1 LAST LOCATION R5D6
J 0
(-330 1250);
DISPLAY 0.617021 (-330 1250);
PAINT AQUA (-330 1250);
FORCEPROP 1 LAST MATERIAL EMPTY
J 0
(-335 1050);
DISPLAY 0.617021 (-335 1050);
PAINT RED (-335 1050);
FORCEPROP 2 LAST CDS_LIB mstr_discrete
J 0
(-375 1125);
PAINT ORANGE (-375 1125);
DISPLAY INVISIBLE (-375 1125);
FORCEPROP 0 LAST ROOM CPU0
J 0
(-325 1350);
DISPLAY 1.021277 (-325 1350);
PAINT ORANGE (-325 1350);
DISPLAY INVISIBLE (-325 1350);
FORCEPROP 1 LAST PATH I312
J 0
(-325 1300);
DISPLAY 0.978723 (-325 1300);
PAINT WHITE (-325 1300);
DISPLAY INVISIBLE (-325 1300);
FORCEPROP 2 LAST SEC 1
J 0
(-325 1350);
DISPLAY 0.680851 (-325 1350);
PAINT MONO (-325 1350);
DISPLAY INVISIBLE (-325 1350);
FORCEPROP 2 LAST SEC_TYPE 0402
J 0
(-325 1350);
DISPLAY 1.021277 (-325 1350);
PAINT ORANGE (-325 1350);
DISPLAY INVISIBLE (-325 1350);
FORCEADD PVCCIO_CPU0..1
(-375 1450);
FORCEPROP 3 LASTPIN (-375 1400) SIG_NAME PVCCIO_CPU0\g
J 0
(-365 1410);
DISPLAY 0.659574 (-365 1410);
PAINT MONO (-365 1410);
DISPLAY INVISIBLE (-365 1410);
FORCEPROP 1 LAST PATH I313
J 0
(-325 1475);
DISPLAY 0.872340 (-325 1475);
PAINT AQUA (-325 1475);
DISPLAY INVISIBLE (-325 1475);
FORCEPROP 1 LAST BODY_TYPE PLUMBING
J 0
(-420 1407);
DISPLAY 0.340426 (-420 1407);
PAINT GREEN (-420 1407);
DISPLAY INVISIBLE (-420 1407);
FORCEPROP 2 LAST CDS_LIB mstr_symbols
J 0
(-375 1450);
PAINT ORANGE (-375 1450);
DISPLAY INVISIBLE (-375 1450);
FORCEPROP 1 LAST VOLTAGE 1.1V
J 0
(-420 1407);
DISPLAY 0.340426 (-420 1407);
PAINT SKYBLUE (-420 1407);
DISPLAY INVISIBLE (-420 1407);
FORCEPROP 1 LAST HDL_POWER PVCCIO_CPU0
J 1
(-375 1500);
DISPLAY 0.872340 (-375 1500);
PAINT GREEN (-375 1500);
DISPLAY INVISIBLE (-375 1500);
FORCEADD PRELIM..10
(-6190 2465);
PAINT GRAY (-6190 2465);
FORCEPROP 1 LAST COMMENT_BODY TRUE
J 0
(-6190 2465);
PAINT ORANGE (-6190 2465);
DISPLAY INVISIBLE (-6190 2465);
FORCEPROP 2 LAST CDS_LIB mstr_misc
J 0
(-6190 2465);
PAINT ORANGE (-6190 2465);
DISPLAY INVISIBLE (-6190 2465);
FORCEADD DESIGN_NOTE..1
(-5200 550);
FORCEPROP 0 LAST L1 CPU SYMBOLS 1-30 ARE PRELIMINARY AND SUBJECT TO CHANGE
J 0
(-5400 425);
DISPLAY 1.021277 (-5400 425);
PAINT ORANGE (-5400 425);
FORCEPROP 2 LAST CDS_LIB mstr_symbols
J 0
(-5200 550);
PAINT ORANGE (-5200 550);
DISPLAY INVISIBLE (-5200 550);
FORCEPROP 1 LAST COMMENT_BODY TRUE
J 0
(-5175 650);
DISPLAY 0.978723 (-5175 650);
PAINT ORANGE (-5175 650);
DISPLAY INVISIBLE (-5175 650);
FORCEADD INTEL_CORP_BPAGE..1
(25 -25);
FORCEPROP 1 LAST CDS_CON_LAST_MODIFIED Tue Dec 01 11:51:23 2015
J 0
(-1400 300);
PAINT ORANGE (-1400 300);
DISPLAY INVISIBLE (-1400 300);
FORCEPROP 1 LAST CUSTOM_TXT_CDS <CURRENT_DESIGN_SHEET> OF <TOTAL_DESIGN_SHEETS>
J 0
(-475 0);
PAINT GREEN (-475 0);
FORCEPROP 1 LAST CUSTOM_TXT_CDS <CON_LAST_MODIFIED>
J 0
(-1900 325);
PAINT GREEN (-1900 325);
FORCEPROP 2 LAST CUSTOM_TXT_CDS <XR_PAGE_TITLE>
J 0
(-7865 5225);
DISPLAY 0.638298 (-7865 5225);
PAINT PINK (-7865 5225);
DISPLAY INVISIBLE (-7865 5225);
FORCEPROP 1 LAST SCH_ADDRESS3 Santa Clara, CA 95052-8119
J 0
(-3950 0);
DISPLAY 0.617021 (-3950 0);
PAINT GREEN (-3950 0);
FORCEPROP 1 LAST SCH_TITLE SKYLAKE - SKT0 - 17 OF 21
J 0
(-7925 25);
DISPLAY 1.212766 (-7925 25);
PAINT GREEN (-7925 25);
FORCEPROP 1 LAST SCH_ADDRESS1 2200 Mission College Blvd.
J 0
(-3950 100);
DISPLAY 0.617021 (-3950 100);
PAINT GREEN (-3950 100);
FORCEPROP 1 LAST SCH_ADDRESS2 P.O. BOX 58119
J 0
(-3950 50);
DISPLAY 0.617021 (-3950 50);
PAINT GREEN (-3950 50);
FORCEPROP 1 LAST SCH_NUMBER H4694802
J 0
(-1275 125);
DISPLAY 1.212766 (-1275 125);
PAINT YELLOW (-1275 125);
FORCEPROP 1 LAST SCH_DEPT BESD
J 1
(-4425 75);
DISPLAY 1.212766 (-4425 75);
PAINT YELLOW (-4425 75);
FORCEPROP 1 LAST SCH_REV 2.420
J 0
(-225 125);
DISPLAY 0.978723 (-225 125);
PAINT YELLOW (-225 125);
FORCEPROP 2 LAST PAGE_BORDER TRUE
J 0
(-7865 5225);
DISPLAY 0.851064 (-7865 5225);
PAINT PINK (-7865 5225);
DISPLAY INVISIBLE (-7865 5225);
FORCEPROP 1 LAST COMMENT_BODY TRUE
J 0
(37 -13);
DISPLAY 0.638298 (37 -13);
PAINT GREEN (37 -13);
DISPLAY INVISIBLE (37 -13);
FORCEPROP 2 LAST CDS_LIB mstr_symbols
J 0
(25 -25);
PAINT ORANGE (25 -25);
DISPLAY INVISIBLE (25 -25);
FORCEPROP 2 LAST CDS_XR_PAGE_TITLE CR-37 : @BASEBOARD_FAB2_LIB.BASEBOARD_FAB2(SCH_1):PAGE37
J 0
(-7865 5225);
DISPLAY 0.638298 (-7865 5225);
PAINT PINK (-7865 5225);
DISPLAY INVISIBLE (-7865 5225);
FORCEADD DNS..2
(-370 1120);
PAINT RED (-370 1120);
FORCEPROP 1 LAST COMMENT_BODY TRUE
R 1
J 0
(-295 895);
DISPLAY 0.872340 (-295 895);
PAINT GREEN (-295 895);
DISPLAY INVISIBLE (-295 895);
FORCEPROP 2 LAST CDS_LIB mstr_misc
J 0
(-370 1120);
PAINT ORANGE (-370 1120);
DISPLAY INVISIBLE (-370 1120);
WIRE 16 -1 (-7125 775)(-6900 775);
WIRE 16 -1 (-7125 825)(-7125 775);
WIRE 16 -1 (-7125 825)(-6900 825);
WIRE 16 -1 (-7125 875)(-7125 825);
WIRE 16 -1 (-7125 875)(-6900 875);
WIRE 16 -1 (-7125 925)(-7125 875);
WIRE 16 -1 (-7125 925)(-6900 925);
WIRE 16 -1 (-7125 975)(-7125 925);
WIRE 16 -1 (-7125 1025)(-7125 975);
WIRE 16 -1 (-7125 975)(-6900 975);
WIRE 16 -1 (-7125 1025)(-6900 1025);
WIRE 16 -1 (-7125 1075)(-7125 1025);
WIRE 16 -1 (-7125 1075)(-6900 1075);
WIRE 16 -1 (-7125 1125)(-7125 1075);
WIRE 16 -1 (-7125 1125)(-6900 1125);
WIRE 16 -1 (-7125 1175)(-7125 1125);
WIRE 16 -1 (-7125 1175)(-6900 1175);
WIRE 16 -1 (-7125 1225)(-7125 1175);
WIRE 16 -1 (-7125 1225)(-6900 1225);
WIRE 16 -1 (-7125 1275)(-7125 1225);
WIRE 16 -1 (-7125 1275)(-6900 1275);
WIRE 16 -1 (-7125 1325)(-7125 1275);
WIRE 16 -1 (-7125 1325)(-6900 1325);
WIRE 16 -1 (-7125 1375)(-7125 1325);
WIRE 16 -1 (-7125 1375)(-6900 1375);
WIRE 16 -1 (-7125 1425)(-7125 1375);
WIRE 16 -1 (-7125 1425)(-6900 1425);
WIRE 16 -1 (-7125 1475)(-7125 1425);
WIRE 16 -1 (-7125 1475)(-6900 1475);
WIRE 16 -1 (-7125 1525)(-7125 1475);
WIRE 16 -1 (-7125 1575)(-7125 1525);
WIRE 16 -1 (-7125 1525)(-6900 1525);
WIRE 16 -1 (-7125 1575)(-6900 1575);
WIRE 16 -1 (-7125 1625)(-7125 1575);
WIRE 16 -1 (-7125 1625)(-6900 1625);
WIRE 16 -1 (-7125 1675)(-7125 1625);
WIRE 16 -1 (-7125 1675)(-6900 1675);
WIRE 16 -1 (-7125 1725)(-7125 1675);
WIRE 16 -1 (-7125 1725)(-6900 1725);
WIRE 16 -1 (-7125 1775)(-7125 1725);
WIRE 16 -1 (-7125 1775)(-6900 1775);
WIRE 16 -1 (-7125 1825)(-7125 1775);
WIRE 16 -1 (-7125 1825)(-6900 1825);
WIRE 16 -1 (-7125 1875)(-7125 1825);
WIRE 16 -1 (-7125 1875)(-6900 1875);
WIRE 16 -1 (-7125 1925)(-7125 1875);
WIRE 16 -1 (-7125 1925)(-6900 1925);
WIRE 16 -1 (-7125 1975)(-7125 1925);
WIRE 16 -1 (-7125 1975)(-6900 1975);
WIRE 16 -1 (-7125 2025)(-7125 1975);
WIRE 16 -1 (-7125 2075)(-7125 2025);
WIRE 16 -1 (-7125 2025)(-6900 2025);
WIRE 16 -1 (-7125 2075)(-6900 2075);
WIRE 16 -1 (-7125 2125)(-7125 2075);
WIRE 16 -1 (-7125 2125)(-6900 2125);
WIRE 16 -1 (-7125 2175)(-7125 2125);
WIRE 16 -1 (-7125 2175)(-6900 2175);
WIRE 16 -1 (-7125 2225)(-7125 2175);
WIRE 16 -1 (-7125 2225)(-6900 2225);
WIRE 16 -1 (-7125 2275)(-7125 2225);
WIRE 16 -1 (-7125 2275)(-6900 2275);
WIRE 16 -1 (-7125 2325)(-7125 2275);
WIRE 16 -1 (-7125 2325)(-6900 2325);
WIRE 16 -1 (-7125 2375)(-7125 2325);
WIRE 16 -1 (-7125 2375)(-6900 2375);
WIRE 16 -1 (-7125 2425)(-7125 2375);
WIRE 16 -1 (-7125 2425)(-6900 2425);
WIRE 16 -1 (-7125 2475)(-7125 2425);
WIRE 16 -1 (-7125 2475)(-6900 2475);
WIRE 16 -1 (-7125 2525)(-7125 2475);
WIRE 16 -1 (-7125 2575)(-7125 2525);
WIRE 16 -1 (-7125 2525)(-6900 2525);
WIRE 16 -1 (-7125 2575)(-6900 2575);
WIRE 16 -1 (-7125 2625)(-7125 2575);
WIRE 16 -1 (-7125 2625)(-6900 2625);
WIRE 16 -1 (-7125 2675)(-7125 2625);
WIRE 16 -1 (-7125 2675)(-6900 2675);
WIRE 16 -1 (-7125 2725)(-7125 2675);
WIRE 16 -1 (-7125 2725)(-6900 2725);
WIRE 16 -1 (-7125 2775)(-7125 2725);
WIRE 16 -1 (-7125 2775)(-6900 2775);
WIRE 16 -1 (-7125 2825)(-7125 2775);
WIRE 16 -1 (-7125 2825)(-6900 2825);
WIRE 16 -1 (-7125 2875)(-7125 2825);
WIRE 16 -1 (-7125 2875)(-6900 2875);
WIRE 16 -1 (-7125 2925)(-7125 2875);
WIRE 16 -1 (-7125 2925)(-6900 2925);
WIRE 16 -1 (-7125 2975)(-7125 2925);
WIRE 16 -1 (-7125 2975)(-6900 2975);
WIRE 16 -1 (-7125 3025)(-7125 2975);
WIRE 16 -1 (-7125 3075)(-7125 3025);
WIRE 16 -1 (-7125 3025)(-6900 3025);
WIRE 16 -1 (-7125 3075)(-6900 3075);
WIRE 16 -1 (-7125 3125)(-7125 3075);
WIRE 16 -1 (-7125 3125)(-6900 3125);
WIRE 16 -1 (-7125 3175)(-7125 3125);
WIRE 16 -1 (-7125 3175)(-6900 3175);
WIRE 16 -1 (-7125 3225)(-7125 3175);
WIRE 16 -1 (-7125 3225)(-6900 3225);
WIRE 16 -1 (-7125 3275)(-7125 3225);
WIRE 16 -1 (-7125 3275)(-6900 3275);
WIRE 16 -1 (-7125 3325)(-7125 3275);
WIRE 16 -1 (-7125 3325)(-6900 3325);
WIRE 16 -1 (-7125 3375)(-7125 3325);
WIRE 16 -1 (-7125 3375)(-6900 3375);
WIRE 16 -1 (-7125 3425)(-7125 3375);
WIRE 16 -1 (-7125 3425)(-6900 3425);
WIRE 16 -1 (-7125 3475)(-7125 3425);
WIRE 16 -1 (-7125 3475)(-6900 3475);
WIRE 16 -1 (-7125 3525)(-7125 3475);
WIRE 16 -1 (-7125 3525)(-6900 3525);
WIRE 16 -1 (-7125 3575)(-7125 3525);
WIRE 16 -1 (-7125 3625)(-7125 3575);
WIRE 16 -1 (-7125 3575)(-6900 3575);
WIRE 16 -1 (-7125 3625)(-6900 3625);
WIRE 16 -1 (-7125 3675)(-7125 3625);
WIRE 16 -1 (-7125 3675)(-6900 3675);
WIRE 16 -1 (-7125 3725)(-7125 3675);
WIRE 16 -1 (-7125 3725)(-6900 3725);
WIRE 16 -1 (-7125 3775)(-7125 3725);
WIRE 16 -1 (-7125 3775)(-6900 3775);
WIRE 16 -1 (-7125 3825)(-7125 3775);
WIRE 16 -1 (-7125 3825)(-6900 3825);
WIRE 16 -1 (-7125 3875)(-7125 3825);
WIRE 16 -1 (-7125 3875)(-6900 3875);
WIRE 16 -1 (-7125 3925)(-7125 3875);
WIRE 16 -1 (-7125 3925)(-6900 3925);
WIRE 16 -1 (-7125 3975)(-7125 3925);
WIRE 16 -1 (-7125 3975)(-6900 3975);
WIRE 16 -1 (-7125 4025)(-7125 3975);
WIRE 16 -1 (-7125 4025)(-6900 4025);
WIRE 16 -1 (-7125 4075)(-7125 4025);
WIRE 16 -1 (-7125 4125)(-7125 4075);
WIRE 16 -1 (-7125 4075)(-6900 4075);
WIRE 16 -1 (-7125 4125)(-6900 4125);
WIRE 16 -1 (-7125 4175)(-7125 4125);
WIRE 16 -1 (-7125 4175)(-6900 4175);
WIRE 16 -1 (-7125 4300)(-7125 4175);
WIRE 16 -1 (-5250 825)(-5250 775);
WIRE 16 -1 (-5250 875)(-5250 825);
WIRE 16 -1 (-5250 825)(-5500 825);
WIRE 16 -1 (-5250 775)(-5500 775);
WIRE 16 -1 (-5250 925)(-5250 875);
WIRE 16 -1 (-5250 875)(-5500 875);
WIRE 16 -1 (-5250 975)(-5250 925);
WIRE 16 -1 (-5250 925)(-5500 925);
WIRE 16 -1 (-5250 1025)(-5250 975);
WIRE 16 -1 (-5250 975)(-5500 975);
WIRE 16 -1 (-5250 1075)(-5250 1025);
WIRE 16 -1 (-5250 1025)(-5500 1025);
WIRE 16 -1 (-5250 1125)(-5250 1075);
WIRE 16 -1 (-5250 1075)(-5500 1075);
WIRE 16 -1 (-5250 1175)(-5250 1125);
WIRE 16 -1 (-5250 1125)(-5500 1125);
WIRE 16 -1 (-5250 1225)(-5250 1175);
WIRE 16 -1 (-5250 1175)(-5500 1175);
WIRE 16 -1 (-5250 1275)(-5250 1225);
WIRE 16 -1 (-5250 1225)(-5500 1225);
WIRE 16 -1 (-5250 1325)(-5250 1275);
WIRE 16 -1 (-5250 1275)(-5500 1275);
WIRE 16 -1 (-5250 1375)(-5250 1325);
WIRE 16 -1 (-5250 1325)(-5500 1325);
WIRE 16 -1 (-5250 1425)(-5250 1375);
WIRE 16 -1 (-5250 1375)(-5500 1375);
WIRE 16 -1 (-5250 1475)(-5250 1425);
WIRE 16 -1 (-5250 1425)(-5500 1425);
WIRE 16 -1 (-5250 1525)(-5250 1475);
WIRE 16 -1 (-5250 1475)(-5500 1475);
WIRE 16 -1 (-5250 1575)(-5250 1525);
WIRE 16 -1 (-5250 1525)(-5500 1525);
WIRE 16 -1 (-5250 1625)(-5250 1575);
WIRE 16 -1 (-5250 1575)(-5500 1575);
WIRE 16 -1 (-5250 1675)(-5250 1625);
WIRE 16 -1 (-5250 1625)(-5500 1625);
WIRE 16 -1 (-5250 1725)(-5250 1675);
WIRE 16 -1 (-5250 1675)(-5500 1675);
WIRE 16 -1 (-5250 1775)(-5250 1725);
WIRE 16 -1 (-5250 1725)(-5500 1725);
WIRE 16 -1 (-5250 1825)(-5250 1775);
WIRE 16 -1 (-5250 1775)(-5500 1775);
WIRE 16 -1 (-5250 1875)(-5250 1825);
WIRE 16 -1 (-5250 1825)(-5500 1825);
WIRE 16 -1 (-5250 1925)(-5250 1875);
WIRE 16 -1 (-5250 1875)(-5500 1875);
WIRE 16 -1 (-5250 1975)(-5250 1925);
WIRE 16 -1 (-5250 1925)(-5500 1925);
WIRE 16 -1 (-5250 2025)(-5250 1975);
WIRE 16 -1 (-5250 1975)(-5500 1975);
WIRE 16 -1 (-5250 2075)(-5250 2025);
WIRE 16 -1 (-5250 2025)(-5500 2025);
WIRE 16 -1 (-5250 2125)(-5250 2075);
WIRE 16 -1 (-5250 2075)(-5500 2075);
WIRE 16 -1 (-5250 2175)(-5250 2125);
WIRE 16 -1 (-5250 2125)(-5500 2125);
WIRE 16 -1 (-5250 2225)(-5250 2175);
WIRE 16 -1 (-5250 2175)(-5500 2175);
WIRE 16 -1 (-5250 2275)(-5250 2225);
WIRE 16 -1 (-5250 2225)(-5500 2225);
WIRE 16 -1 (-5250 2325)(-5250 2275);
WIRE 16 -1 (-5250 2275)(-5500 2275);
WIRE 16 -1 (-5250 2375)(-5250 2325);
WIRE 16 -1 (-5250 2325)(-5500 2325);
WIRE 16 -1 (-5250 2425)(-5250 2375);
WIRE 16 -1 (-5250 2375)(-5500 2375);
WIRE 16 -1 (-5250 2475)(-5250 2425);
WIRE 16 -1 (-5250 2425)(-5500 2425);
WIRE 16 -1 (-5250 2525)(-5250 2475);
WIRE 16 -1 (-5250 2475)(-5500 2475);
WIRE 16 -1 (-5250 2575)(-5250 2525);
WIRE 16 -1 (-5250 2525)(-5500 2525);
WIRE 16 -1 (-5250 2625)(-5250 2575);
WIRE 16 -1 (-5250 2575)(-5500 2575);
WIRE 16 -1 (-5250 2675)(-5250 2625);
WIRE 16 -1 (-5250 2625)(-5500 2625);
WIRE 16 -1 (-5250 2725)(-5250 2675);
WIRE 16 -1 (-5250 2675)(-5500 2675);
WIRE 16 -1 (-5250 2775)(-5250 2725);
WIRE 16 -1 (-5250 2725)(-5500 2725);
WIRE 16 -1 (-5250 2825)(-5250 2775);
WIRE 16 -1 (-5250 2775)(-5500 2775);
WIRE 16 -1 (-5250 2875)(-5250 2825);
WIRE 16 -1 (-5250 2825)(-5500 2825);
WIRE 16 -1 (-5250 2925)(-5250 2875);
WIRE 16 -1 (-5250 2875)(-5500 2875);
WIRE 16 -1 (-5250 2975)(-5250 2925);
WIRE 16 -1 (-5250 2925)(-5500 2925);
WIRE 16 -1 (-5250 3025)(-5250 2975);
WIRE 16 -1 (-5250 2975)(-5500 2975);
WIRE 16 -1 (-5250 3075)(-5250 3025);
WIRE 16 -1 (-5250 3025)(-5500 3025);
WIRE 16 -1 (-5250 3125)(-5250 3075);
WIRE 16 -1 (-5250 3075)(-5500 3075);
WIRE 16 -1 (-5250 3175)(-5250 3125);
WIRE 16 -1 (-5250 3125)(-5500 3125);
WIRE 16 -1 (-5250 3225)(-5250 3175);
WIRE 16 -1 (-5250 3175)(-5500 3175);
WIRE 16 -1 (-5250 3275)(-5250 3225);
WIRE 16 -1 (-5250 3225)(-5500 3225);
WIRE 16 -1 (-5250 3325)(-5250 3275);
WIRE 16 -1 (-5250 3275)(-5500 3275);
WIRE 16 -1 (-5250 3375)(-5250 3325);
WIRE 16 -1 (-5250 3325)(-5500 3325);
WIRE 16 -1 (-5250 3425)(-5250 3375);
WIRE 16 -1 (-5250 3375)(-5500 3375);
WIRE 16 -1 (-5250 3475)(-5250 3425);
WIRE 16 -1 (-5250 3425)(-5500 3425);
WIRE 16 -1 (-5250 3525)(-5250 3475);
WIRE 16 -1 (-5250 3475)(-5500 3475);
WIRE 16 -1 (-5250 3575)(-5250 3525);
WIRE 16 -1 (-5250 3525)(-5500 3525);
WIRE 16 -1 (-5250 3625)(-5250 3575);
WIRE 16 -1 (-5250 3575)(-5500 3575);
WIRE 16 -1 (-5250 3675)(-5250 3625);
WIRE 16 -1 (-5250 3625)(-5500 3625);
WIRE 16 -1 (-5250 3725)(-5250 3675);
WIRE 16 -1 (-5250 3675)(-5500 3675);
WIRE 16 -1 (-5250 3775)(-5250 3725);
WIRE 16 -1 (-5250 3725)(-5500 3725);
WIRE 16 -1 (-5250 3825)(-5250 3775);
WIRE 16 -1 (-5250 3775)(-5500 3775);
WIRE 16 -1 (-5250 3875)(-5250 3825);
WIRE 16 -1 (-5250 3825)(-5500 3825);
WIRE 16 -1 (-5250 3925)(-5250 3875);
WIRE 16 -1 (-5250 3875)(-5500 3875);
WIRE 16 -1 (-5250 3975)(-5250 3925);
WIRE 16 -1 (-5250 3925)(-5500 3925);
WIRE 16 -1 (-5250 4025)(-5250 3975);
WIRE 16 -1 (-5250 3975)(-5500 3975);
WIRE 16 -1 (-5250 4075)(-5250 4025);
WIRE 16 -1 (-5250 4025)(-5500 4025);
WIRE 16 -1 (-5250 4125)(-5250 4075);
WIRE 16 -1 (-5250 4075)(-5500 4075);
WIRE 16 -1 (-5250 4175)(-5250 4125);
WIRE 16 -1 (-5250 4125)(-5500 4125);
WIRE 16 -1 (-5250 4225)(-5250 4175);
WIRE 16 -1 (-5250 4175)(-5500 4175);
WIRE 16 -1 (-3375 775)(-3125 775);
WIRE 16 -1 (-3375 825)(-3375 775);
WIRE 16 -1 (-3375 825)(-3125 825);
WIRE 16 -1 (-3375 875)(-3375 825);
WIRE 16 -1 (-3375 875)(-3125 875);
WIRE 16 -1 (-3375 925)(-3375 875);
WIRE 16 -1 (-3375 925)(-3125 925);
WIRE 16 -1 (-3375 975)(-3375 925);
WIRE 16 -1 (-3375 1025)(-3375 975);
WIRE 16 -1 (-3375 975)(-3125 975);
WIRE 16 -1 (-3375 1025)(-3125 1025);
WIRE 16 -1 (-3375 1075)(-3375 1025);
WIRE 16 -1 (-3375 1075)(-3125 1075);
WIRE 16 -1 (-3375 1125)(-3375 1075);
WIRE 16 -1 (-3375 1125)(-3125 1125);
WIRE 16 -1 (-3375 1175)(-3375 1125);
WIRE 16 -1 (-3375 1175)(-3125 1175);
WIRE 16 -1 (-3375 1225)(-3375 1175);
WIRE 16 -1 (-3375 1225)(-3125 1225);
WIRE 16 -1 (-3375 1275)(-3375 1225);
WIRE 16 -1 (-3375 1275)(-3125 1275);
WIRE 16 -1 (-3375 1325)(-3375 1275);
WIRE 16 -1 (-3375 1325)(-3125 1325);
WIRE 16 -1 (-3375 1375)(-3375 1325);
WIRE 16 -1 (-3375 1375)(-3125 1375);
WIRE 16 -1 (-3375 1425)(-3375 1375);
WIRE 16 -1 (-3375 1425)(-3125 1425);
WIRE 16 -1 (-3375 1475)(-3375 1425);
WIRE 16 -1 (-3375 1475)(-3125 1475);
WIRE 16 -1 (-3375 1525)(-3375 1475);
WIRE 16 -1 (-3375 1575)(-3375 1525);
WIRE 16 -1 (-3375 1525)(-3125 1525);
WIRE 16 -1 (-3375 1575)(-3125 1575);
WIRE 16 -1 (-3375 1625)(-3375 1575);
WIRE 16 -1 (-3375 1625)(-3125 1625);
WIRE 16 -1 (-3375 1675)(-3375 1625);
WIRE 16 -1 (-3375 1675)(-3125 1675);
WIRE 16 -1 (-3375 1725)(-3375 1675);
WIRE 16 -1 (-3375 1725)(-3125 1725);
WIRE 16 -1 (-3375 1775)(-3375 1725);
WIRE 16 -1 (-3375 1775)(-3125 1775);
WIRE 16 -1 (-3375 1825)(-3375 1775);
WIRE 16 -1 (-3375 1825)(-3125 1825);
WIRE 16 -1 (-3375 1875)(-3375 1825);
WIRE 16 -1 (-3375 1875)(-3125 1875);
WIRE 16 -1 (-3375 1925)(-3375 1875);
WIRE 16 -1 (-3375 1925)(-3125 1925);
WIRE 16 -1 (-3375 1975)(-3375 1925);
WIRE 16 -1 (-3375 1975)(-3125 1975);
WIRE 16 -1 (-3375 2025)(-3375 1975);
WIRE 16 -1 (-3375 2075)(-3375 2025);
WIRE 16 -1 (-3375 2025)(-3125 2025);
WIRE 16 -1 (-3375 2075)(-3125 2075);
WIRE 16 -1 (-3375 2125)(-3375 2075);
WIRE 16 -1 (-3375 2125)(-3125 2125);
WIRE 16 -1 (-3375 2175)(-3375 2125);
WIRE 16 -1 (-3375 2175)(-3125 2175);
WIRE 16 -1 (-3375 2225)(-3375 2175);
WIRE 16 -1 (-3375 2225)(-3125 2225);
WIRE 16 -1 (-3375 2275)(-3375 2225);
WIRE 16 -1 (-3375 2275)(-3125 2275);
WIRE 16 -1 (-3375 2325)(-3375 2275);
WIRE 16 -1 (-3375 2325)(-3125 2325);
WIRE 16 -1 (-3375 2375)(-3375 2325);
WIRE 16 -1 (-3375 2375)(-3125 2375);
WIRE 16 -1 (-3375 2425)(-3375 2375);
WIRE 16 -1 (-3375 2425)(-3125 2425);
WIRE 16 -1 (-3375 2475)(-3375 2425);
WIRE 16 -1 (-3375 2475)(-3125 2475);
WIRE 16 -1 (-3375 2525)(-3375 2475);
WIRE 16 -1 (-3375 2575)(-3375 2525);
WIRE 16 -1 (-3375 2525)(-3125 2525);
WIRE 16 -1 (-3375 2575)(-3125 2575);
WIRE 16 -1 (-3375 2625)(-3375 2575);
WIRE 16 -1 (-3375 2625)(-3125 2625);
WIRE 16 -1 (-3375 2675)(-3375 2625);
WIRE 16 -1 (-3375 2675)(-3125 2675);
WIRE 16 -1 (-3375 2725)(-3375 2675);
WIRE 16 -1 (-3375 2725)(-3125 2725);
WIRE 16 -1 (-3375 2775)(-3375 2725);
WIRE 16 -1 (-3375 2775)(-3125 2775);
WIRE 16 -1 (-3375 2825)(-3375 2775);
WIRE 16 -1 (-3375 2825)(-3125 2825);
WIRE 16 -1 (-3375 2875)(-3375 2825);
WIRE 16 -1 (-3375 2875)(-3125 2875);
WIRE 16 -1 (-3375 2925)(-3375 2875);
WIRE 16 -1 (-3375 2925)(-3125 2925);
WIRE 16 -1 (-3375 2975)(-3375 2925);
WIRE 16 -1 (-3375 2975)(-3125 2975);
WIRE 16 -1 (-3375 3025)(-3375 2975);
WIRE 16 -1 (-3375 3075)(-3375 3025);
WIRE 16 -1 (-3375 3025)(-3125 3025);
WIRE 16 -1 (-3375 3075)(-3125 3075);
WIRE 16 -1 (-3375 3125)(-3375 3075);
WIRE 16 -1 (-3375 3125)(-3125 3125);
WIRE 16 -1 (-3375 3175)(-3375 3125);
WIRE 16 -1 (-3375 3175)(-3125 3175);
WIRE 16 -1 (-3375 3225)(-3375 3175);
WIRE 16 -1 (-3375 3225)(-3125 3225);
WIRE 16 -1 (-3375 3275)(-3375 3225);
WIRE 16 -1 (-3375 3275)(-3125 3275);
WIRE 16 -1 (-3375 3325)(-3375 3275);
WIRE 16 -1 (-3375 3325)(-3125 3325);
WIRE 16 -1 (-3375 3375)(-3375 3325);
WIRE 16 -1 (-3375 3375)(-3125 3375);
WIRE 16 -1 (-3375 3425)(-3375 3375);
WIRE 16 -1 (-3375 3425)(-3125 3425);
WIRE 16 -1 (-3375 3475)(-3375 3425);
WIRE 16 -1 (-3375 3475)(-3125 3475);
WIRE 16 -1 (-3375 3525)(-3375 3475);
WIRE 16 -1 (-3375 3525)(-3125 3525);
WIRE 16 -1 (-3375 3575)(-3375 3525);
WIRE 16 -1 (-3375 3625)(-3375 3575);
WIRE 16 -1 (-3375 3575)(-3125 3575);
WIRE 16 -1 (-3375 3625)(-3125 3625);
WIRE 16 -1 (-3375 3675)(-3375 3625);
WIRE 16 -1 (-3375 3675)(-3125 3675);
WIRE 16 -1 (-3375 3725)(-3375 3675);
WIRE 16 -1 (-3375 3725)(-3125 3725);
WIRE 16 -1 (-3375 3775)(-3375 3725);
WIRE 16 -1 (-3375 3775)(-3125 3775);
WIRE 16 -1 (-3375 3825)(-3375 3775);
WIRE 16 -1 (-3375 3825)(-3125 3825);
WIRE 16 -1 (-3375 3875)(-3375 3825);
WIRE 16 -1 (-3375 3875)(-3125 3875);
WIRE 16 -1 (-3375 3925)(-3375 3875);
WIRE 16 -1 (-3375 3925)(-3125 3925);
WIRE 16 -1 (-3375 3975)(-3375 3925);
WIRE 16 -1 (-3375 3975)(-3125 3975);
WIRE 16 -1 (-3375 4025)(-3375 3975);
WIRE 16 -1 (-3375 4025)(-3125 4025);
WIRE 16 -1 (-3375 4075)(-3375 4025);
WIRE 16 -1 (-3375 4125)(-3375 4075);
WIRE 16 -1 (-3375 4075)(-3125 4075);
WIRE 16 -1 (-3375 4125)(-3125 4125);
WIRE 16 -1 (-3375 4175)(-3375 4125);
WIRE 16 -1 (-3375 4175)(-3125 4175);
WIRE 16 -1 (-3375 4300)(-3375 4175);
WIRE 16 -1 (-1500 1225)(-1500 1175);
WIRE 16 -1 (-1500 1275)(-1500 1225);
WIRE 16 -1 (-1500 1225)(-1725 1225);
WIRE 16 -1 (-1500 1175)(-1725 1175);
WIRE 16 -1 (-1500 1325)(-1500 1275);
WIRE 16 -1 (-1500 1275)(-1725 1275);
WIRE 16 -1 (-1500 1375)(-1500 1325);
WIRE 16 -1 (-1500 1325)(-1725 1325);
WIRE 16 -1 (-1500 1425)(-1500 1375);
WIRE 16 -1 (-1500 1375)(-1725 1375);
WIRE 16 -1 (-1500 1475)(-1500 1425);
WIRE 16 -1 (-1500 1425)(-1725 1425);
WIRE 16 -1 (-1500 1525)(-1500 1475);
WIRE 16 -1 (-1500 1475)(-1725 1475);
WIRE 16 -1 (-1500 1575)(-1500 1525);
WIRE 16 -1 (-1500 1525)(-1725 1525);
WIRE 16 -1 (-1500 1625)(-1500 1575);
WIRE 16 -1 (-1500 1575)(-1725 1575);
WIRE 16 -1 (-1500 1675)(-1500 1625);
WIRE 16 -1 (-1500 1625)(-1725 1625);
WIRE 16 -1 (-1500 1725)(-1500 1675);
WIRE 16 -1 (-1500 1675)(-1725 1675);
WIRE 16 -1 (-1500 1775)(-1500 1725);
WIRE 16 -1 (-1500 1725)(-1725 1725);
WIRE 16 -1 (-1500 1825)(-1500 1775);
WIRE 16 -1 (-1500 1775)(-1725 1775);
WIRE 16 -1 (-1500 1875)(-1500 1825);
WIRE 16 -1 (-1500 1825)(-1725 1825);
WIRE 16 -1 (-1500 1925)(-1500 1875);
WIRE 16 -1 (-1500 1875)(-1725 1875);
WIRE 16 -1 (-1500 1975)(-1500 1925);
WIRE 16 -1 (-1500 1925)(-1725 1925);
WIRE 16 -1 (-1500 2025)(-1500 1975);
WIRE 16 -1 (-1500 1975)(-1725 1975);
WIRE 16 -1 (-1500 2075)(-1500 2025);
WIRE 16 -1 (-1500 2025)(-1725 2025);
WIRE 16 -1 (-1500 2125)(-1500 2075);
WIRE 16 -1 (-1500 2075)(-1725 2075);
WIRE 16 -1 (-1500 2175)(-1500 2125);
WIRE 16 -1 (-1500 2125)(-1725 2125);
WIRE 16 -1 (-1500 2225)(-1500 2175);
WIRE 16 -1 (-1500 2175)(-1725 2175);
WIRE 16 -1 (-1500 2275)(-1500 2225);
WIRE 16 -1 (-1500 2225)(-1725 2225);
WIRE 16 -1 (-1500 2325)(-1500 2275);
WIRE 16 -1 (-1500 2275)(-1725 2275);
WIRE 16 -1 (-1500 2375)(-1500 2325);
WIRE 16 -1 (-1500 2325)(-1725 2325);
WIRE 16 -1 (-1500 2425)(-1500 2375);
WIRE 16 -1 (-1500 2375)(-1725 2375);
WIRE 16 -1 (-1500 2475)(-1500 2425);
WIRE 16 -1 (-1500 2425)(-1725 2425);
WIRE 16 -1 (-1500 2525)(-1500 2475);
WIRE 16 -1 (-1500 2475)(-1725 2475);
WIRE 16 -1 (-1500 2575)(-1500 2525);
WIRE 16 -1 (-1500 2525)(-1725 2525);
WIRE 16 -1 (-1500 2625)(-1500 2575);
WIRE 16 -1 (-1500 2575)(-1725 2575);
WIRE 16 -1 (-1500 2675)(-1500 2625);
WIRE 16 -1 (-1500 2625)(-1725 2625);
WIRE 16 -1 (-1500 2725)(-1500 2675);
WIRE 16 -1 (-1500 2675)(-1725 2675);
WIRE 16 -1 (-1500 2775)(-1500 2725);
WIRE 16 -1 (-1500 2725)(-1725 2725);
WIRE 16 -1 (-1500 2825)(-1500 2775);
WIRE 16 -1 (-1500 2775)(-1725 2775);
WIRE 16 -1 (-1500 2875)(-1500 2825);
WIRE 16 -1 (-1500 2825)(-1725 2825);
WIRE 16 -1 (-1500 2925)(-1500 2875);
WIRE 16 -1 (-1500 2875)(-1725 2875);
WIRE 16 -1 (-1500 2975)(-1500 2925);
WIRE 16 -1 (-1500 2925)(-1725 2925);
WIRE 16 -1 (-1500 3025)(-1500 2975);
WIRE 16 -1 (-1500 2975)(-1725 2975);
WIRE 16 -1 (-1500 3075)(-1500 3025);
WIRE 16 -1 (-1500 3025)(-1725 3025);
WIRE 16 -1 (-1500 3125)(-1500 3075);
WIRE 16 -1 (-1500 3075)(-1725 3075);
WIRE 16 -1 (-1500 3175)(-1500 3125);
WIRE 16 -1 (-1500 3125)(-1725 3125);
WIRE 16 -1 (-1500 3225)(-1500 3175);
WIRE 16 -1 (-1500 3175)(-1725 3175);
WIRE 16 -1 (-1500 3275)(-1500 3225);
WIRE 16 -1 (-1500 3225)(-1725 3225);
WIRE 16 -1 (-1500 3325)(-1500 3275);
WIRE 16 -1 (-1500 3275)(-1725 3275);
WIRE 16 -1 (-1500 3375)(-1500 3325);
WIRE 16 -1 (-1500 3325)(-1725 3325);
WIRE 16 -1 (-1500 3425)(-1500 3375);
WIRE 16 -1 (-1500 3375)(-1725 3375);
WIRE 16 -1 (-1500 3475)(-1500 3425);
WIRE 16 -1 (-1500 3425)(-1725 3425);
WIRE 16 -1 (-1500 3525)(-1500 3475);
WIRE 16 -1 (-1500 3475)(-1725 3475);
WIRE 16 -1 (-1500 3575)(-1500 3525);
WIRE 16 -1 (-1500 3525)(-1725 3525);
WIRE 16 -1 (-1500 3625)(-1500 3575);
WIRE 16 -1 (-1500 3575)(-1725 3575);
WIRE 16 -1 (-1500 3675)(-1500 3625);
WIRE 16 -1 (-1500 3625)(-1725 3625);
WIRE 16 -1 (-1500 3725)(-1500 3675);
WIRE 16 -1 (-1500 3675)(-1725 3675);
WIRE 16 -1 (-1500 3775)(-1500 3725);
WIRE 16 -1 (-1500 3725)(-1725 3725);
WIRE 16 -1 (-1500 3825)(-1500 3775);
WIRE 16 -1 (-1500 3775)(-1725 3775);
WIRE 16 -1 (-1500 3875)(-1500 3825);
WIRE 16 -1 (-1500 3825)(-1725 3825);
WIRE 16 -1 (-1500 3925)(-1500 3875);
WIRE 16 -1 (-1500 3875)(-1725 3875);
WIRE 16 -1 (-1500 3975)(-1500 3925);
WIRE 16 -1 (-1500 3925)(-1725 3925);
WIRE 16 -1 (-1500 4025)(-1500 3975);
WIRE 16 -1 (-1500 3975)(-1725 3975);
WIRE 16 -1 (-1500 4075)(-1500 4025);
WIRE 16 -1 (-1500 4025)(-1725 4025);
WIRE 16 -1 (-1500 4125)(-1500 4075);
WIRE 16 -1 (-1500 4075)(-1725 4075);
WIRE 16 -1 (-1500 4175)(-1500 4125);
WIRE 16 -1 (-1500 4125)(-1725 4125);
WIRE 16 -1 (-1500 4275)(-1500 4175);
WIRE 16 -1 (-1500 4175)(-1725 4175);
WIRE 16 -1 (-375 650)(-375 575);
WIRE 16 -1 (-775 1450)(-775 1575);
WIRE 16 -1 (-375 1225)(-375 1400);
WIRE 16 -1 (-775 1075)(-775 1250);
WIRE 16 -1 (-775 1075)(-775 975);
WIRE 16 -1 (-775 1075)(-1725 1075);
FORCEPROP 0 LAST SIG_NAME VSENSE_VCCINR2PMAX_CPU0
J 0
(-1550 1085);
DISPLAY 0.617021 (-1550 1085);
PAINT ORANGE (-1550 1085);
FORCEPROP 2 LASTPROP $XRERR UNIQUE?
J 0
(-1790 1085);
DISPLAY 0.638298 (-1790 1085);
PAINT MONO (-1790 1085);
DISPLAY INVISIBLE (-1790 1085);
WIRE 16 -1 (-775 975)(-1725 975);
WIRE 16 -1 (-375 875)(-375 1025);
WIRE 16 -1 (-375 850)(-375 875);
WIRE 16 -1 (-375 875)(-1725 875);
FORCEPROP 0 LAST SIG_NAME VSENSE_PMAX_CPU0
J 0
(-1550 885);
DISPLAY 0.617021 (-1550 885);
PAINT ORANGE (-1550 885);
FORCEPROP 2 LASTPROP $XRERR UNIQUE?
J 0
(-1790 885);
DISPLAY 0.638298 (-1790 885);
PAINT MONO (-1790 885);
DISPLAY INVISIBLE (-1790 885);
WIRE 16 -1 (-800 725)(-1725 725);
FORCEPROP 0 LAST SIG_NAME VSENSE_PVCCIN_CPU0_SKT_VRTN
J 0
(-1550 725);
DISPLAY 0.617021 (-1550 725);
PAINT ORANGE (-1550 725);
WIRE 16 -1 (-800 775)(-1725 775);
FORCEPROP 0 LAST SIG_NAME VSENSE_PVCCIN_CPU0_SKT_VSEN
J 0
(-1550 784);
DISPLAY 0.617021 (-1550 784);
PAINT ORANGE (-1550 784);
DOT 1 (-7125 825);
DOT 1 (-7125 875);
DOT 1 (-7125 925);
DOT 1 (-7125 975);
DOT 1 (-7125 1025);
DOT 1 (-7125 1075);
DOT 1 (-7125 1125);
DOT 1 (-7125 1175);
DOT 1 (-7125 1225);
DOT 1 (-7125 1275);
DOT 1 (-7125 1325);
DOT 1 (-7125 1375);
DOT 1 (-7125 1425);
DOT 1 (-7125 1475);
DOT 1 (-7125 1525);
DOT 1 (-7125 1625);
DOT 1 (-7125 1575);
DOT 1 (-7125 1675);
DOT 1 (-7125 1725);
DOT 1 (-7125 1775);
DOT 1 (-7125 1825);
DOT 1 (-7125 1875);
DOT 1 (-7125 1925);
DOT 1 (-7125 1975);
DOT 1 (-7125 2025);
DOT 1 (-7125 2075);
DOT 1 (-7125 2125);
DOT 1 (-7125 2175);
DOT 1 (-7125 2275);
DOT 1 (-7125 2225);
DOT 1 (-7125 2325);
DOT 1 (-7125 2375);
DOT 1 (-7125 2425);
DOT 1 (-7125 2525);
DOT 1 (-7125 2475);
DOT 1 (-7125 2575);
DOT 1 (-7125 2625);
DOT 1 (-7125 2675);
DOT 1 (-7125 2725);
DOT 1 (-7125 2775);
DOT 1 (-7125 2825);
DOT 1 (-7125 2875);
DOT 1 (-7125 2925);
DOT 1 (-7125 2975);
DOT 1 (-7125 3025);
DOT 1 (-7125 3075);
DOT 1 (-7125 3125);
DOT 1 (-7125 3175);
DOT 1 (-7125 3225);
DOT 1 (-7125 3275);
DOT 1 (-7125 3325);
DOT 1 (-7125 3375);
DOT 1 (-7125 3425);
DOT 1 (-7125 3475);
DOT 1 (-7125 3525);
DOT 1 (-7125 3575);
DOT 1 (-7125 3675);
DOT 1 (-7125 3625);
DOT 1 (-7125 3725);
DOT 1 (-7125 3775);
DOT 1 (-7125 3825);
DOT 1 (-7125 3875);
DOT 1 (-7125 3925);
DOT 1 (-7125 3975);
DOT 1 (-7125 4025);
DOT 1 (-7125 4075);
DOT 1 (-5250 825);
DOT 1 (-5250 875);
DOT 1 (-5250 975);
DOT 1 (-5250 925);
DOT 1 (-5250 1025);
DOT 1 (-5250 1125);
DOT 1 (-5250 1075);
DOT 1 (-5250 1175);
DOT 1 (-5250 1225);
DOT 1 (-5250 1275);
DOT 1 (-5250 1325);
DOT 1 (-5250 1375);
DOT 1 (-5250 1475);
DOT 1 (-5250 1525);
DOT 1 (-5250 1425);
DOT 1 (-5250 1625);
DOT 1 (-5250 1575);
DOT 1 (-5250 1675);
DOT 1 (-5250 1725);
DOT 1 (-5250 1775);
DOT 1 (-5250 1825);
DOT 1 (-5250 1875);
DOT 1 (-5250 1925);
DOT 1 (-5250 2025);
DOT 1 (-5250 1975);
DOT 1 (-5250 2125);
DOT 1 (-5250 2075);
DOT 1 (-5250 2175);
DOT 1 (-5250 2275);
DOT 1 (-5250 2225);
DOT 1 (-5250 2425);
DOT 1 (-5250 2375);
DOT 1 (-5250 2325);
DOT 1 (-5250 2475);
DOT 1 (-5250 2525);
DOT 1 (-5250 2625);
DOT 1 (-5250 2575);
DOT 1 (-5250 2675);
DOT 1 (-5250 2775);
DOT 1 (-5250 2725);
DOT 1 (-5250 2825);
DOT 1 (-5250 2925);
DOT 1 (-5250 2875);
DOT 1 (-5250 3025);
DOT 1 (-5250 2975);
DOT 1 (-5250 3075);
DOT 1 (-5250 3175);
DOT 1 (-5250 3125);
DOT 1 (-5250 3225);
DOT 1 (-5250 3325);
DOT 1 (-5250 3275);
DOT 1 (-5250 3375);
DOT 1 (-5250 3425);
DOT 1 (-5250 3525);
DOT 1 (-5250 3575);
DOT 1 (-5250 3475);
DOT 1 (-5250 3625);
DOT 1 (-5250 3675);
DOT 1 (-5250 3725);
DOT 1 (-5250 3775);
DOT 1 (-5250 3825);
DOT 1 (-5250 3875);
DOT 1 (-5250 3925);
DOT 1 (-5250 3975);
DOT 1 (-5250 4075);
DOT 1 (-5250 4025);
DOT 1 (-7125 4175);
DOT 1 (-7125 4125);
DOT 1 (-5250 4175);
DOT 1 (-5250 4125);
DOT 1 (-3375 825);
DOT 1 (-3375 875);
DOT 1 (-3375 975);
DOT 1 (-3375 925);
DOT 1 (-3375 1025);
DOT 1 (-3375 1075);
DOT 1 (-3375 1125);
DOT 1 (-3375 1175);
DOT 1 (-3375 1225);
DOT 1 (-3375 1275);
DOT 1 (-3375 1375);
DOT 1 (-3375 1325);
DOT 1 (-3375 1425);
DOT 1 (-3375 1475);
DOT 1 (-3375 1525);
DOT 1 (-3375 1625);
DOT 1 (-3375 1575);
DOT 1 (-3375 1675);
DOT 1 (-3375 1725);
DOT 1 (-3375 1775);
DOT 1 (-3375 1875);
DOT 1 (-3375 1825);
DOT 1 (-3375 1925);
DOT 1 (-3375 1975);
DOT 1 (-3375 2025);
DOT 1 (-3375 2075);
DOT 1 (-3375 2125);
DOT 1 (-3375 2175);
DOT 1 (-3375 2275);
DOT 1 (-3375 2225);
DOT 1 (-3375 2325);
DOT 1 (-3375 2375);
DOT 1 (-3375 2425);
DOT 1 (-3375 2475);
DOT 1 (-3375 2525);
DOT 1 (-3375 2575);
DOT 1 (-3375 2625);
DOT 1 (-3375 2675);
DOT 1 (-3375 2775);
DOT 1 (-3375 2725);
DOT 1 (-3375 2825);
DOT 1 (-3375 2875);
DOT 1 (-3375 2925);
DOT 1 (-3375 2975);
DOT 1 (-3375 3025);
DOT 1 (-3375 3075);
DOT 1 (-3375 3125);
DOT 1 (-3375 3175);
DOT 1 (-3375 3225);
DOT 1 (-3375 3275);
DOT 1 (-3375 3325);
DOT 1 (-3375 3425);
DOT 1 (-3375 3375);
DOT 1 (-3375 3475);
DOT 1 (-3375 3525);
DOT 1 (-3375 3575);
DOT 1 (-3375 3625);
DOT 1 (-3375 3675);
DOT 1 (-3375 3725);
DOT 1 (-3375 3775);
DOT 1 (-3375 3825);
DOT 1 (-3375 3875);
DOT 1 (-3375 3925);
DOT 1 (-3375 3975);
DOT 1 (-3375 4025);
DOT 1 (-3375 4075);
DOT 1 (-1500 1275);
DOT 1 (-1500 1225);
DOT 1 (-1500 1325);
DOT 1 (-1500 1375);
DOT 1 (-1500 1425);
DOT 1 (-1500 1475);
DOT 1 (-1500 1525);
DOT 1 (-1500 1575);
DOT 1 (-1500 1625);
DOT 1 (-1500 1675);
DOT 1 (-1500 1725);
DOT 1 (-1500 1775);
DOT 1 (-1500 1825);
DOT 1 (-1500 1875);
DOT 1 (-1500 1925);
DOT 1 (-1500 1975);
DOT 1 (-1500 2025);
DOT 1 (-375 875);
DOT 1 (-775 1075);
DOT 1 (-1500 2075);
DOT 1 (-1500 2125);
DOT 1 (-1500 2175);
DOT 1 (-1500 2275);
DOT 1 (-1500 2225);
DOT 1 (-1500 2325);
DOT 1 (-1500 2375);
DOT 1 (-1500 2425);
DOT 1 (-1500 2475);
DOT 1 (-1500 2525);
DOT 1 (-1500 2575);
DOT 1 (-1500 2625);
DOT 1 (-1500 2675);
DOT 1 (-1500 2775);
DOT 1 (-1500 2725);
DOT 1 (-1500 2825);
DOT 1 (-1500 2875);
DOT 1 (-1500 2925);
DOT 1 (-1500 3025);
DOT 1 (-1500 2975);
DOT 1 (-1500 3075);
DOT 1 (-1500 3125);
DOT 1 (-1500 3175);
DOT 1 (-1500 3225);
DOT 1 (-1500 3275);
DOT 1 (-1500 3325);
DOT 1 (-1500 3425);
DOT 1 (-1500 3375);
DOT 1 (-1500 3475);
DOT 1 (-1500 3525);
DOT 1 (-1500 3575);
DOT 1 (-1500 3675);
DOT 1 (-1500 3625);
DOT 1 (-1500 3725);
DOT 1 (-1500 3775);
DOT 1 (-1500 3825);
DOT 1 (-1500 3925);
DOT 1 (-1500 3875);
DOT 1 (-1500 3975);
DOT 1 (-1500 4025);
DOT 1 (-1500 4075);
DOT 1 (-3375 4125);
DOT 1 (-3375 4175);
DOT 1 (-1500 4125);
DOT 1 (-1500 4175);
FORCENOTE
ROOM=CPU0
(-7925 325) 0;
DISPLAY LEFT (-7925 325);
DISPLAY 1.382979 (-7925 325);
PAINT PURPLE (-7925 325);
FORCENOTE
BOM_COST=PROC_SOCKET
(-7925 225) 0;
DISPLAY LEFT (-7925 225);
DISPLAY 1.382979 (-7925 225);
PAINT PURPLE (-7925 225);
QUIT
